FILE_TYPE = MACRO_DRAWING;
SET COLOR_WIRE YELLOW;
SET COLOR_PROP ORANGE;
SET COLOR_DOT WHITE;
SET COLOR_ARC YELLOW;
SET COLOR_BODY GREEN;
SET COLOR_NOTE PURPLE;
SET PROP_DISPLAY VALUE;
SET PAGE_NUMBER P24;
FORCEADD GENOA_SP5..15
(-4925 5000);
FORCEPROP 1 LAST LOCATION U25
J 0
(-6020 6256);
DISPLAY 0.489362 (-6020 6256);
PAINT SKYBLUE (-6020 6256);
FORCEPROP 0 LAST $SEC 15
J 0
(-6000 6300);
DISPLAY 0.680851 (-6000 6300);
PAINT MONO (-6000 6300);
DISPLAY INVISIBLE (-6000 6300);
FORCEPROP 0 LAST CDS_SEC 15
J 0
(-6025 6225);
DISPLAY 1.021277 (-6025 6225);
DISPLAY INVISIBLE (-6025 6225);
FORCEPROP 0 LASTPIN (-6175 5750) $PN BW53
J 2
(-6185 5760);
DISPLAY 0.489362 (-6185 5760);
PAINT MONO (-6185 5760);
FORCEPROP 0 LASTPIN (-6175 5650) $PN CA53
J 2
(-6185 5660);
DISPLAY 0.489362 (-6185 5660);
PAINT MONO (-6185 5660);
FORCEPROP 0 LASTPIN (-6175 5550) $PN BU53
J 2
(-6185 5560);
DISPLAY 0.489362 (-6185 5560);
PAINT MONO (-6185 5560);
FORCEPROP 0 LASTPIN (-6175 5450) $PN BW50
J 2
(-6185 5460);
DISPLAY 0.489362 (-6185 5460);
PAINT MONO (-6185 5460);
FORCEPROP 0 LASTPIN (-6175 5350) $PN CA50
J 2
(-6185 5360);
DISPLAY 0.489362 (-6185 5360);
PAINT MONO (-6185 5360);
FORCEPROP 0 LASTPIN (-6175 5250) $PN BU50
J 2
(-6185 5260);
DISPLAY 0.489362 (-6185 5260);
PAINT MONO (-6185 5260);
FORCEPROP 0 LASTPIN (-6175 5150) $PN BW47
J 2
(-6185 5160);
DISPLAY 0.489362 (-6185 5160);
PAINT MONO (-6185 5160);
FORCEPROP 0 LASTPIN (-6175 5050) $PN CA47
J 2
(-6185 5060);
DISPLAY 0.489362 (-6185 5060);
PAINT MONO (-6185 5060);
FORCEPROP 0 LASTPIN (-6175 4950) $PN BU47
J 2
(-6185 4960);
DISPLAY 0.489362 (-6185 4960);
PAINT MONO (-6185 4960);
FORCEPROP 0 LASTPIN (-6175 4850) $PN BW44
J 2
(-6185 4860);
DISPLAY 0.489362 (-6185 4860);
PAINT MONO (-6185 4860);
FORCEPROP 0 LASTPIN (-6175 4750) $PN CA44
J 2
(-6185 4760);
DISPLAY 0.489362 (-6185 4760);
PAINT MONO (-6185 4760);
FORCEPROP 0 LASTPIN (-6175 4650) $PN BU44
J 2
(-6185 4660);
DISPLAY 0.489362 (-6185 4660);
PAINT MONO (-6185 4660);
FORCEPROP 0 LASTPIN (-6175 4550) $PN BY41
J 2
(-6185 4560);
DISPLAY 0.489362 (-6185 4560);
PAINT MONO (-6185 4560);
FORCEPROP 0 LASTPIN (-6175 4450) $PN CB41
J 2
(-6185 4460);
DISPLAY 0.489362 (-6185 4460);
PAINT MONO (-6185 4460);
FORCEPROP 0 LASTPIN (-6175 4350) $PN BV41
J 2
(-6185 4360);
DISPLAY 0.489362 (-6185 4360);
PAINT MONO (-6185 4360);
FORCEPROP 0 LASTPIN (-6175 4250) $PN BT41
J 2
(-6185 4260);
DISPLAY 0.489362 (-6185 4260);
PAINT MONO (-6185 4260);
FORCEPROP 0 LASTPIN (-6175 5800) $PN BW52
J 2
(-6185 5810);
DISPLAY 0.489362 (-6185 5810);
PAINT MONO (-6185 5810);
FORCEPROP 0 LASTPIN (-6175 5700) $PN CA52
J 2
(-6185 5710);
DISPLAY 0.489362 (-6185 5710);
PAINT MONO (-6185 5710);
FORCEPROP 0 LASTPIN (-6175 5600) $PN BU52
J 2
(-6185 5610);
DISPLAY 0.489362 (-6185 5610);
PAINT MONO (-6185 5610);
FORCEPROP 0 LASTPIN (-6175 5500) $PN BW49
J 2
(-6185 5510);
DISPLAY 0.489362 (-6185 5510);
PAINT MONO (-6185 5510);
FORCEPROP 0 LASTPIN (-6175 5400) $PN CA49
J 2
(-6185 5410);
DISPLAY 0.489362 (-6185 5410);
PAINT MONO (-6185 5410);
FORCEPROP 0 LASTPIN (-6175 5300) $PN BU49
J 2
(-6185 5310);
DISPLAY 0.489362 (-6185 5310);
PAINT MONO (-6185 5310);
FORCEPROP 0 LASTPIN (-6175 5200) $PN BW46
J 2
(-6185 5210);
DISPLAY 0.489362 (-6185 5210);
PAINT MONO (-6185 5210);
FORCEPROP 0 LASTPIN (-6175 5100) $PN CA46
J 2
(-6185 5110);
DISPLAY 0.489362 (-6185 5110);
PAINT MONO (-6185 5110);
FORCEPROP 0 LASTPIN (-6175 5000) $PN BU46
J 2
(-6185 5010);
DISPLAY 0.489362 (-6185 5010);
PAINT MONO (-6185 5010);
FORCEPROP 0 LASTPIN (-6175 4900) $PN BW43
J 2
(-6185 4910);
DISPLAY 0.489362 (-6185 4910);
PAINT MONO (-6185 4910);
FORCEPROP 0 LASTPIN (-6175 4800) $PN CA43
J 2
(-6185 4810);
DISPLAY 0.489362 (-6185 4810);
PAINT MONO (-6185 4810);
FORCEPROP 0 LASTPIN (-6175 4700) $PN BU43
J 2
(-6185 4710);
DISPLAY 0.489362 (-6185 4710);
PAINT MONO (-6185 4710);
FORCEPROP 0 LASTPIN (-6175 4600) $PN BY40
J 2
(-6185 4610);
DISPLAY 0.489362 (-6185 4610);
PAINT MONO (-6185 4610);
FORCEPROP 0 LASTPIN (-6175 4500) $PN CB40
J 2
(-6185 4510);
DISPLAY 0.489362 (-6185 4510);
PAINT MONO (-6185 4510);
FORCEPROP 0 LASTPIN (-6175 4400) $PN BV40
J 2
(-6185 4410);
DISPLAY 0.489362 (-6185 4410);
PAINT MONO (-6185 4410);
FORCEPROP 0 LASTPIN (-6175 4300) $PN BT40
J 2
(-6185 4310);
DISPLAY 0.489362 (-6185 4310);
PAINT MONO (-6185 4310);
FORCEPROP 0 LASTPIN (-3675 5750) $PN CN52
J 0
(-3665 5760);
DISPLAY 0.489362 (-3665 5760);
PAINT MONO (-3665 5760);
FORCEPROP 0 LASTPIN (-3675 5650) $PN CR52
J 0
(-3665 5660);
DISPLAY 0.489362 (-3665 5660);
PAINT MONO (-3665 5660);
FORCEPROP 0 LASTPIN (-3675 5550) $PN CL52
J 0
(-3665 5560);
DISPLAY 0.489362 (-3665 5560);
PAINT MONO (-3665 5560);
FORCEPROP 0 LASTPIN (-3675 5450) $PN CN49
J 0
(-3665 5460);
DISPLAY 0.489362 (-3665 5460);
PAINT MONO (-3665 5460);
FORCEPROP 0 LASTPIN (-3675 5350) $PN CR49
J 0
(-3665 5360);
DISPLAY 0.489362 (-3665 5360);
PAINT MONO (-3665 5360);
FORCEPROP 0 LASTPIN (-3675 5250) $PN CU49
J 0
(-3665 5260);
DISPLAY 0.489362 (-3665 5260);
PAINT MONO (-3665 5260);
FORCEPROP 0 LASTPIN (-3675 5150) $PN CL49
J 0
(-3665 5160);
DISPLAY 0.489362 (-3665 5160);
PAINT MONO (-3665 5160);
FORCEPROP 0 LASTPIN (-3675 5050) $PN CR46
J 0
(-3665 5060);
DISPLAY 0.489362 (-3665 5060);
PAINT MONO (-3665 5060);
FORCEPROP 0 LASTPIN (-3675 4950) $PN CU46
J 0
(-3665 4960);
DISPLAY 0.489362 (-3665 4960);
PAINT MONO (-3665 4960);
FORCEPROP 0 LASTPIN (-3675 4850) $PN CN46
J 0
(-3665 4860);
DISPLAY 0.489362 (-3665 4860);
PAINT MONO (-3665 4860);
FORCEPROP 0 LASTPIN (-3675 4750) $PN CR43
J 0
(-3665 4760);
DISPLAY 0.489362 (-3665 4760);
PAINT MONO (-3665 4760);
FORCEPROP 0 LASTPIN (-3675 4650) $PN CU43
J 0
(-3665 4660);
DISPLAY 0.489362 (-3665 4660);
PAINT MONO (-3665 4660);
FORCEPROP 0 LASTPIN (-3675 4550) $PN CN43
J 0
(-3665 4560);
DISPLAY 0.489362 (-3665 4560);
PAINT MONO (-3665 4560);
FORCEPROP 0 LASTPIN (-3675 4450) $PN CT40
J 0
(-3665 4460);
DISPLAY 0.489362 (-3665 4460);
PAINT MONO (-3665 4460);
FORCEPROP 0 LASTPIN (-3675 4350) $PN CP40
J 0
(-3665 4360);
DISPLAY 0.489362 (-3665 4360);
PAINT MONO (-3665 4360);
FORCEPROP 0 LASTPIN (-3675 4250) $PN CM40
J 0
(-3665 4260);
DISPLAY 0.489362 (-3665 4260);
PAINT MONO (-3665 4260);
FORCEPROP 0 LASTPIN (-3675 5800) $PN CN53
J 0
(-3665 5810);
DISPLAY 0.489362 (-3665 5810);
PAINT MONO (-3665 5810);
FORCEPROP 0 LASTPIN (-3675 5700) $PN CR53
J 0
(-3665 5710);
DISPLAY 0.489362 (-3665 5710);
PAINT MONO (-3665 5710);
FORCEPROP 0 LASTPIN (-3675 5600) $PN CL53
J 0
(-3665 5610);
DISPLAY 0.489362 (-3665 5610);
PAINT MONO (-3665 5610);
FORCEPROP 0 LASTPIN (-3675 5500) $PN CN50
J 0
(-3665 5510);
DISPLAY 0.489362 (-3665 5510);
PAINT MONO (-3665 5510);
FORCEPROP 0 LASTPIN (-3675 5400) $PN CR50
J 0
(-3665 5410);
DISPLAY 0.489362 (-3665 5410);
PAINT MONO (-3665 5410);
FORCEPROP 0 LASTPIN (-3675 5300) $PN CU50
J 0
(-3665 5310);
DISPLAY 0.489362 (-3665 5310);
PAINT MONO (-3665 5310);
FORCEPROP 0 LASTPIN (-3675 5200) $PN CL50
J 0
(-3665 5210);
DISPLAY 0.489362 (-3665 5210);
PAINT MONO (-3665 5210);
FORCEPROP 0 LASTPIN (-3675 5100) $PN CR47
J 0
(-3665 5110);
DISPLAY 0.489362 (-3665 5110);
PAINT MONO (-3665 5110);
FORCEPROP 0 LASTPIN (-3675 5000) $PN CU47
J 0
(-3665 5010);
DISPLAY 0.489362 (-3665 5010);
PAINT MONO (-3665 5010);
FORCEPROP 0 LASTPIN (-3675 4900) $PN CN47
J 0
(-3665 4910);
DISPLAY 0.489362 (-3665 4910);
PAINT MONO (-3665 4910);
FORCEPROP 0 LASTPIN (-3675 4800) $PN CR44
J 0
(-3665 4810);
DISPLAY 0.489362 (-3665 4810);
PAINT MONO (-3665 4810);
FORCEPROP 0 LASTPIN (-3675 4700) $PN CU44
J 0
(-3665 4710);
DISPLAY 0.489362 (-3665 4710);
PAINT MONO (-3665 4710);
FORCEPROP 0 LASTPIN (-3675 4600) $PN CN44
J 0
(-3665 4610);
DISPLAY 0.489362 (-3665 4610);
PAINT MONO (-3665 4610);
FORCEPROP 0 LASTPIN (-3675 4500) $PN CT41
J 0
(-3665 4510);
DISPLAY 0.489362 (-3665 4510);
PAINT MONO (-3665 4510);
FORCEPROP 0 LASTPIN (-3675 4400) $PN CP41
J 0
(-3665 4410);
DISPLAY 0.489362 (-3665 4410);
PAINT MONO (-3665 4410);
FORCEPROP 0 LASTPIN (-3675 4300) $PN CM41
J 0
(-3665 4310);
DISPLAY 0.489362 (-3665 4310);
PAINT MONO (-3665 4310);
FORCEPROP 2 LAST VALUE SOCKET6096_13568-001
J 0
(-6025 6053);
DISPLAY 0.489362 (-6025 6053);
PAINT SKYBLUE (-6025 6053);
FORCEPROP 1 LAST MATERIAL IO
J 0
(-6020 5982);
DISPLAY 0.489362 (-6020 5982);
PAINT SKYBLUE (-6020 5982);
FORCEPROP 2 LAST PART_TYPE SMLF
J 0
(-6025 6153);
DISPLAY 1.021277 (-6025 6153);
FORCEPROP 2 LAST CDS_LIB pure_quanta
J 0
(-4925 5000);
DISPLAY INVISIBLE (-4925 5000);
FORCEPROP 1 LAST NEEDS_NO_SIZE TRUE
J 0
(-4925 5000);
DISPLAY 0.723404 (-4925 5000);
PAINT GREEN (-4925 5000);
DISPLAY INVISIBLE (-4925 5000);
FORCEPROP 1 LAST CDS_LMAN_SYM_OUTLINE -1100,950,1100,-950
J 0
(-4925 5000);
DISPLAY 0.468085 (-4925 5000);
PAINT GREEN (-4925 5000);
DISPLAY INVISIBLE (-4925 5000);
FORCEPROP 1 LAST PATH I148
J 0
(-4925 5000);
DISPLAY 0.723404 (-4925 5000);
PAINT GREEN (-4925 5000);
DISPLAY INVISIBLE (-4925 5000);
FORCEPROP 1 LAST PART_NUMBER DGA^6000030
J 0
(-6020 6109);
DISPLAY 0.489362 (-6020 6109);
PAINT SKYBLUE (-6020 6109);
DISPLAY INVISIBLE (-6020 6109);
FORCEADD GENOA_SP5..16
(-5000 1525);
FORCEPROP 1 LAST LOCATION U25
J 0
(-6100 2781);
DISPLAY 0.489362 (-6100 2781);
PAINT SKYBLUE (-6100 2781);
FORCEPROP 0 LAST $SEC 16
J 0
(-6075 2825);
DISPLAY 0.680851 (-6075 2825);
PAINT MONO (-6075 2825);
DISPLAY INVISIBLE (-6075 2825);
FORCEPROP 0 LAST CDS_SEC 16
J 0
(-6100 2675);
DISPLAY 1.021277 (-6100 2675);
DISPLAY INVISIBLE (-6100 2675);
FORCEPROP 0 LASTPIN (-6250 2275) $PN CE53
J 2
(-6260 2285);
DISPLAY 0.489362 (-6260 2285);
PAINT MONO (-6260 2285);
FORCEPROP 0 LASTPIN (-6250 2175) $PN CG53
J 2
(-6260 2185);
DISPLAY 0.489362 (-6260 2185);
PAINT MONO (-6260 2185);
FORCEPROP 0 LASTPIN (-6250 2075) $PN CC53
J 2
(-6260 2085);
DISPLAY 0.489362 (-6260 2085);
PAINT MONO (-6260 2085);
FORCEPROP 0 LASTPIN (-6250 1975) $PN CE50
J 2
(-6260 1985);
DISPLAY 0.489362 (-6260 1985);
PAINT MONO (-6260 1985);
FORCEPROP 0 LASTPIN (-6250 1875) $PN CG50
J 2
(-6260 1885);
DISPLAY 0.489362 (-6260 1885);
PAINT MONO (-6260 1885);
FORCEPROP 0 LASTPIN (-6250 1775) $PN CC50
J 2
(-6260 1785);
DISPLAY 0.489362 (-6260 1785);
PAINT MONO (-6260 1785);
FORCEPROP 0 LASTPIN (-6250 1675) $PN CE47
J 2
(-6260 1685);
DISPLAY 0.489362 (-6260 1685);
PAINT MONO (-6260 1685);
FORCEPROP 0 LASTPIN (-6250 1575) $PN CG47
J 2
(-6260 1585);
DISPLAY 0.489362 (-6260 1585);
PAINT MONO (-6260 1585);
FORCEPROP 0 LASTPIN (-6250 1475) $PN CC47
J 2
(-6260 1485);
DISPLAY 0.489362 (-6260 1485);
PAINT MONO (-6260 1485);
FORCEPROP 0 LASTPIN (-6250 1375) $PN CE44
J 2
(-6260 1385);
DISPLAY 0.489362 (-6260 1385);
PAINT MONO (-6260 1385);
FORCEPROP 0 LASTPIN (-6250 1275) $PN CG44
J 2
(-6260 1285);
DISPLAY 0.489362 (-6260 1285);
PAINT MONO (-6260 1285);
FORCEPROP 0 LASTPIN (-6250 1175) $PN CJ44
J 2
(-6260 1185);
DISPLAY 0.489362 (-6260 1185);
PAINT MONO (-6260 1185);
FORCEPROP 0 LASTPIN (-6250 1075) $PN CC44
J 2
(-6260 1085);
DISPLAY 0.489362 (-6260 1085);
PAINT MONO (-6260 1085);
FORCEPROP 0 LASTPIN (-6250 975) $PN CH41
J 2
(-6260 985);
DISPLAY 0.489362 (-6260 985);
PAINT MONO (-6260 985);
FORCEPROP 0 LASTPIN (-6250 875) $PN CF41
J 2
(-6260 885);
DISPLAY 0.489362 (-6260 885);
PAINT MONO (-6260 885);
FORCEPROP 0 LASTPIN (-6250 775) $PN CD41
J 2
(-6260 785);
DISPLAY 0.489362 (-6260 785);
PAINT MONO (-6260 785);
FORCEPROP 0 LASTPIN (-6250 2325) $PN CE52
J 2
(-6260 2335);
DISPLAY 0.489362 (-6260 2335);
PAINT MONO (-6260 2335);
FORCEPROP 0 LASTPIN (-6250 2225) $PN CG52
J 2
(-6260 2235);
DISPLAY 0.489362 (-6260 2235);
PAINT MONO (-6260 2235);
FORCEPROP 0 LASTPIN (-6250 2125) $PN CC52
J 2
(-6260 2135);
DISPLAY 0.489362 (-6260 2135);
PAINT MONO (-6260 2135);
FORCEPROP 0 LASTPIN (-6250 2025) $PN CE49
J 2
(-6260 2035);
DISPLAY 0.489362 (-6260 2035);
PAINT MONO (-6260 2035);
FORCEPROP 0 LASTPIN (-6250 1925) $PN CG49
J 2
(-6260 1935);
DISPLAY 0.489362 (-6260 1935);
PAINT MONO (-6260 1935);
FORCEPROP 0 LASTPIN (-6250 1825) $PN CC49
J 2
(-6260 1835);
DISPLAY 0.489362 (-6260 1835);
PAINT MONO (-6260 1835);
FORCEPROP 0 LASTPIN (-6250 1725) $PN CE46
J 2
(-6260 1735);
DISPLAY 0.489362 (-6260 1735);
PAINT MONO (-6260 1735);
FORCEPROP 0 LASTPIN (-6250 1625) $PN CG46
J 2
(-6260 1635);
DISPLAY 0.489362 (-6260 1635);
PAINT MONO (-6260 1635);
FORCEPROP 0 LASTPIN (-6250 1525) $PN CC46
J 2
(-6260 1535);
DISPLAY 0.489362 (-6260 1535);
PAINT MONO (-6260 1535);
FORCEPROP 0 LASTPIN (-6250 1425) $PN CE43
J 2
(-6260 1435);
DISPLAY 0.489362 (-6260 1435);
PAINT MONO (-6260 1435);
FORCEPROP 0 LASTPIN (-6250 1325) $PN CG43
J 2
(-6260 1335);
DISPLAY 0.489362 (-6260 1335);
PAINT MONO (-6260 1335);
FORCEPROP 0 LASTPIN (-6250 1225) $PN CJ43
J 2
(-6260 1235);
DISPLAY 0.489362 (-6260 1235);
PAINT MONO (-6260 1235);
FORCEPROP 0 LASTPIN (-6250 1125) $PN CC43
J 2
(-6260 1135);
DISPLAY 0.489362 (-6260 1135);
PAINT MONO (-6260 1135);
FORCEPROP 0 LASTPIN (-6250 1025) $PN CH40
J 2
(-6260 1035);
DISPLAY 0.489362 (-6260 1035);
PAINT MONO (-6260 1035);
FORCEPROP 0 LASTPIN (-6250 925) $PN CF40
J 2
(-6260 935);
DISPLAY 0.489362 (-6260 935);
PAINT MONO (-6260 935);
FORCEPROP 0 LASTPIN (-6250 825) $PN CD40
J 2
(-6260 835);
DISPLAY 0.489362 (-6260 835);
PAINT MONO (-6260 835);
FORCEPROP 0 LASTPIN (-3750 2275) $PN CU52
J 0
(-3740 2285);
DISPLAY 0.489362 (-3740 2285);
PAINT MONO (-3740 2285);
FORCEPROP 0 LASTPIN (-3750 2175) $PN DA52
J 0
(-3740 2185);
DISPLAY 0.489362 (-3740 2185);
PAINT MONO (-3740 2185);
FORCEPROP 0 LASTPIN (-3750 2075) $PN DC52
J 0
(-3740 2085);
DISPLAY 0.489362 (-3740 2085);
PAINT MONO (-3740 2085);
FORCEPROP 0 LASTPIN (-3750 1975) $PN CW52
J 0
(-3740 1985);
DISPLAY 0.489362 (-3740 1985);
PAINT MONO (-3740 1985);
FORCEPROP 0 LASTPIN (-3750 1875) $PN DA49
J 0
(-3740 1885);
DISPLAY 0.489362 (-3740 1885);
PAINT MONO (-3740 1885);
FORCEPROP 0 LASTPIN (-3750 1775) $PN DC49
J 0
(-3740 1785);
DISPLAY 0.489362 (-3740 1785);
PAINT MONO (-3740 1785);
FORCEPROP 0 LASTPIN (-3750 1675) $PN CW49
J 0
(-3740 1685);
DISPLAY 0.489362 (-3740 1685);
PAINT MONO (-3740 1685);
FORCEPROP 0 LASTPIN (-3750 1575) $PN DA46
J 0
(-3740 1585);
DISPLAY 0.489362 (-3740 1585);
PAINT MONO (-3740 1585);
FORCEPROP 0 LASTPIN (-3750 1475) $PN DC46
J 0
(-3740 1485);
DISPLAY 0.489362 (-3740 1485);
PAINT MONO (-3740 1485);
FORCEPROP 0 LASTPIN (-3750 1375) $PN CW46
J 0
(-3740 1385);
DISPLAY 0.489362 (-3740 1385);
PAINT MONO (-3740 1385);
FORCEPROP 0 LASTPIN (-3750 1275) $PN DA43
J 0
(-3740 1285);
DISPLAY 0.489362 (-3740 1285);
PAINT MONO (-3740 1285);
FORCEPROP 0 LASTPIN (-3750 1175) $PN DC43
J 0
(-3740 1185);
DISPLAY 0.489362 (-3740 1185);
PAINT MONO (-3740 1185);
FORCEPROP 0 LASTPIN (-3750 1075) $PN CW43
J 0
(-3740 1085);
DISPLAY 0.489362 (-3740 1085);
PAINT MONO (-3740 1085);
FORCEPROP 0 LASTPIN (-3750 975) $PN DB40
J 0
(-3740 985);
DISPLAY 0.489362 (-3740 985);
PAINT MONO (-3740 985);
FORCEPROP 0 LASTPIN (-3750 875) $PN CY40
J 0
(-3740 885);
DISPLAY 0.489362 (-3740 885);
PAINT MONO (-3740 885);
FORCEPROP 0 LASTPIN (-3750 775) $PN CV40
J 0
(-3740 785);
DISPLAY 0.489362 (-3740 785);
PAINT MONO (-3740 785);
FORCEPROP 0 LASTPIN (-3750 2325) $PN CU53
J 0
(-3740 2335);
DISPLAY 0.489362 (-3740 2335);
PAINT MONO (-3740 2335);
FORCEPROP 0 LASTPIN (-3750 2225) $PN DA53
J 0
(-3740 2235);
DISPLAY 0.489362 (-3740 2235);
PAINT MONO (-3740 2235);
FORCEPROP 0 LASTPIN (-3750 2125) $PN DC53
J 0
(-3740 2135);
DISPLAY 0.489362 (-3740 2135);
PAINT MONO (-3740 2135);
FORCEPROP 0 LASTPIN (-3750 2025) $PN CW53
J 0
(-3740 2035);
DISPLAY 0.489362 (-3740 2035);
PAINT MONO (-3740 2035);
FORCEPROP 0 LASTPIN (-3750 1925) $PN DA50
J 0
(-3740 1935);
DISPLAY 0.489362 (-3740 1935);
PAINT MONO (-3740 1935);
FORCEPROP 0 LASTPIN (-3750 1825) $PN DC50
J 0
(-3740 1835);
DISPLAY 0.489362 (-3740 1835);
PAINT MONO (-3740 1835);
FORCEPROP 0 LASTPIN (-3750 1725) $PN CW50
J 0
(-3740 1735);
DISPLAY 0.489362 (-3740 1735);
PAINT MONO (-3740 1735);
FORCEPROP 0 LASTPIN (-3750 1625) $PN DA47
J 0
(-3740 1635);
DISPLAY 0.489362 (-3740 1635);
PAINT MONO (-3740 1635);
FORCEPROP 0 LASTPIN (-3750 1525) $PN DC47
J 0
(-3740 1535);
DISPLAY 0.489362 (-3740 1535);
PAINT MONO (-3740 1535);
FORCEPROP 0 LASTPIN (-3750 1425) $PN CW47
J 0
(-3740 1435);
DISPLAY 0.489362 (-3740 1435);
PAINT MONO (-3740 1435);
FORCEPROP 0 LASTPIN (-3750 1325) $PN DA44
J 0
(-3740 1335);
DISPLAY 0.489362 (-3740 1335);
PAINT MONO (-3740 1335);
FORCEPROP 0 LASTPIN (-3750 1225) $PN DC44
J 0
(-3740 1235);
DISPLAY 0.489362 (-3740 1235);
PAINT MONO (-3740 1235);
FORCEPROP 0 LASTPIN (-3750 1125) $PN CW44
J 0
(-3740 1135);
DISPLAY 0.489362 (-3740 1135);
PAINT MONO (-3740 1135);
FORCEPROP 0 LASTPIN (-3750 1025) $PN DB41
J 0
(-3740 1035);
DISPLAY 0.489362 (-3740 1035);
PAINT MONO (-3740 1035);
FORCEPROP 0 LASTPIN (-3750 925) $PN CY41
J 0
(-3740 935);
DISPLAY 0.489362 (-3740 935);
PAINT MONO (-3740 935);
FORCEPROP 0 LASTPIN (-3750 825) $PN CV41
J 0
(-3740 835);
DISPLAY 0.489362 (-3740 835);
PAINT MONO (-3740 835);
FORCEPROP 2 LAST PART_TYPE SMLF
J 0
(-6100 2700);
DISPLAY 1.021277 (-6100 2700);
FORCEPROP 1 LAST MATERIAL IO
J 0
(-6100 2507);
DISPLAY 0.489362 (-6100 2507);
PAINT SKYBLUE (-6100 2507);
FORCEPROP 2 LAST VALUE SOCKET6096_13568-001
J 0
(-6100 2575);
DISPLAY 0.489362 (-6100 2575);
PAINT SKYBLUE (-6100 2575);
FORCEPROP 1 LAST CDS_LMAN_SYM_OUTLINE -1100,950,1100,-950
J 0
(-5000 1525);
DISPLAY 0.468085 (-5000 1525);
PAINT GREEN (-5000 1525);
DISPLAY INVISIBLE (-5000 1525);
FORCEPROP 1 LAST NEEDS_NO_SIZE TRUE
J 0
(-5000 1525);
DISPLAY 0.723404 (-5000 1525);
PAINT GREEN (-5000 1525);
DISPLAY INVISIBLE (-5000 1525);
FORCEPROP 2 LAST CDS_LIB pure_quanta
J 0
(-5000 1525);
DISPLAY INVISIBLE (-5000 1525);
FORCEPROP 1 LAST PATH I149
J 0
(-5000 1525);
DISPLAY 0.723404 (-5000 1525);
PAINT GREEN (-5000 1525);
DISPLAY INVISIBLE (-5000 1525);
FORCEPROP 1 LAST PART_NUMBER DGA^6000030
J 0
(-6100 2634);
DISPLAY 0.489362 (-6100 2634);
PAINT SKYBLUE (-6100 2634);
DISPLAY INVISIBLE (-6100 2634);
FORCEADD OFFPAGE..2
(-1800 2550);
FORCEPROP 2 LAST $XR0 63 
J 0
(-1611 2550);
DISPLAY 0.638298 (-1611 2550);
PAINT MONO (-1611 2550);
FORCEPROP 2 LAST CDS_LIB standard
J 0
(-1800 2550);
DISPLAY INVISIBLE (-1800 2550);
FORCEPROP 1 LAST OFFPAGE TRUE
J 0
(-1475 2425);
DISPLAY 0.872340 (-1475 2425);
PAINT GREEN (-1475 2425);
DISPLAY INVISIBLE (-1475 2425);
FORCEPROP 1 LAST COMMENT_BODY TRUE
J 0
(-1845 2455);
DISPLAY 0.872340 (-1845 2455);
PAINT GREEN (-1845 2455);
DISPLAY INVISIBLE (-1845 2455);
FORCEPROP 2 LAST PATH I218
J 0
(-1500 2600);
DISPLAY 1.021277 (-1500 2600);
DISPLAY INVISIBLE (-1500 2600);
FORCEADD OFFPAGE..2
(-1800 2500);
FORCEPROP 2 LAST $XR0 63 
J 0
(-1611 2500);
DISPLAY 0.638298 (-1611 2500);
PAINT MONO (-1611 2500);
FORCEPROP 2 LAST CDS_LIB standard
J 0
(-1800 2500);
DISPLAY INVISIBLE (-1800 2500);
FORCEPROP 1 LAST OFFPAGE TRUE
J 0
(-1475 2375);
DISPLAY 0.872340 (-1475 2375);
PAINT GREEN (-1475 2375);
DISPLAY INVISIBLE (-1475 2375);
FORCEPROP 1 LAST COMMENT_BODY TRUE
J 0
(-1845 2405);
DISPLAY 0.872340 (-1845 2405);
PAINT GREEN (-1845 2405);
DISPLAY INVISIBLE (-1845 2405);
FORCEPROP 2 LAST PATH I219
J 0
(-1500 2550);
DISPLAY 1.021277 (-1500 2550);
DISPLAY INVISIBLE (-1500 2550);
FORCEADD TAP..6
R 2
(-3175 2275);
FORCEPROP 3 LASTPIN (-3225 2275) SIG_NAME P5E_CPU0_P1_TX_DN<0>
J 0
(-3215 2285);
DISPLAY 0.659574 (-3215 2285);
PAINT MONO (-3215 2285);
DISPLAY INVISIBLE (-3215 2285);
FORCEPROP 1 LASTPIN (-3225 2275) BN 0
J 2
(-3173 2283);
DISPLAY 0.489362 (-3173 2283);
PAINT MONO (-3173 2283);
FORCEPROP 2 LAST ROOM RISER1
J 0
(-3675 2325);
DISPLAY 0.829787 (-3675 2325);
PAINT RED (-3675 2325);
DISPLAY INVISIBLE (-3675 2325);
FORCEPROP 2 LAST CDS_LIB mstr_standard
J 0
(-3175 2275);
DISPLAY INVISIBLE (-3175 2275);
FORCEPROP 2 LAST BOM_COST IO_SLOT
J 0
(-3675 2375);
DISPLAY 0.829787 (-3675 2375);
DISPLAY INVISIBLE (-3675 2375);
FORCEPROP 1 LAST BODY_TYPE PLUMBING
J 2
(-3175 2225);
DISPLAY 0.702128 (-3175 2225);
PAINT GREEN (-3175 2225);
DISPLAY INVISIBLE (-3175 2225);
FORCEPROP 1 LAST HDL_TAP TRUE
J 2
(-3500 2150);
DISPLAY 0.702128 (-3500 2150);
PAINT GREEN (-3500 2150);
DISPLAY INVISIBLE (-3500 2150);
FORCEPROP 1 LAST PATH I220
J 2
(-3173 2275);
DISPLAY 0.872340 (-3173 2275);
PAINT GREEN (-3173 2275);
DISPLAY INVISIBLE (-3173 2275);
FORCEADD TAP..6
R 2
(-3175 2175);
FORCEPROP 3 LASTPIN (-3225 2175) SIG_NAME P5E_CPU0_P1_TX_DN<1>
J 0
(-3215 2185);
DISPLAY 0.659574 (-3215 2185);
PAINT MONO (-3215 2185);
DISPLAY INVISIBLE (-3215 2185);
FORCEPROP 1 LASTPIN (-3225 2175) BN 1
J 2
(-3173 2183);
DISPLAY 0.489362 (-3173 2183);
PAINT MONO (-3173 2183);
FORCEPROP 2 LAST ROOM RISER1
J 0
(-3675 2225);
DISPLAY 0.829787 (-3675 2225);
PAINT RED (-3675 2225);
DISPLAY INVISIBLE (-3675 2225);
FORCEPROP 2 LAST BOM_COST IO_SLOT
J 0
(-3675 2275);
DISPLAY 0.829787 (-3675 2275);
DISPLAY INVISIBLE (-3675 2275);
FORCEPROP 2 LAST CDS_LIB mstr_standard
J 0
(-3175 2175);
DISPLAY INVISIBLE (-3175 2175);
FORCEPROP 1 LAST BODY_TYPE PLUMBING
J 2
(-3175 2125);
DISPLAY 0.702128 (-3175 2125);
PAINT GREEN (-3175 2125);
DISPLAY INVISIBLE (-3175 2125);
FORCEPROP 1 LAST HDL_TAP TRUE
J 2
(-3500 2050);
DISPLAY 0.702128 (-3500 2050);
PAINT GREEN (-3500 2050);
DISPLAY INVISIBLE (-3500 2050);
FORCEPROP 1 LAST PATH I221
J 2
(-3173 2175);
DISPLAY 0.872340 (-3173 2175);
PAINT GREEN (-3173 2175);
DISPLAY INVISIBLE (-3173 2175);
FORCEADD TAP..6
R 2
(-3325 2225);
FORCEPROP 3 LASTPIN (-3375 2225) SIG_NAME P5E_CPU0_P1_TX_DP<1>
J 0
(-3365 2235);
DISPLAY 0.659574 (-3365 2235);
PAINT MONO (-3365 2235);
DISPLAY INVISIBLE (-3365 2235);
FORCEPROP 1 LASTPIN (-3375 2225) BN 1
J 2
(-3323 2233);
DISPLAY 0.489362 (-3323 2233);
PAINT MONO (-3323 2233);
FORCEPROP 2 LAST ROOM RISER1
J 0
(-3825 2275);
DISPLAY 0.829787 (-3825 2275);
PAINT RED (-3825 2275);
DISPLAY INVISIBLE (-3825 2275);
FORCEPROP 2 LAST BOM_COST IO_SLOT
J 0
(-3825 2325);
DISPLAY 0.829787 (-3825 2325);
DISPLAY INVISIBLE (-3825 2325);
FORCEPROP 2 LAST CDS_LIB mstr_standard
J 0
(-3325 2225);
DISPLAY INVISIBLE (-3325 2225);
FORCEPROP 1 LAST BODY_TYPE PLUMBING
J 2
(-3325 2175);
DISPLAY 0.702128 (-3325 2175);
PAINT GREEN (-3325 2175);
DISPLAY INVISIBLE (-3325 2175);
FORCEPROP 1 LAST HDL_TAP TRUE
J 2
(-3650 2100);
DISPLAY 0.702128 (-3650 2100);
PAINT GREEN (-3650 2100);
DISPLAY INVISIBLE (-3650 2100);
FORCEPROP 1 LAST PATH I222
J 2
(-3323 2225);
DISPLAY 0.872340 (-3323 2225);
PAINT GREEN (-3323 2225);
DISPLAY INVISIBLE (-3323 2225);
FORCEADD TAP..6
R 2
(-3325 2325);
FORCEPROP 3 LASTPIN (-3375 2325) SIG_NAME P5E_CPU0_P1_TX_DP<0>
J 0
(-3365 2335);
DISPLAY 0.659574 (-3365 2335);
PAINT MONO (-3365 2335);
DISPLAY INVISIBLE (-3365 2335);
FORCEPROP 1 LASTPIN (-3375 2325) BN 0
J 2
(-3323 2333);
DISPLAY 0.489362 (-3323 2333);
PAINT MONO (-3323 2333);
FORCEPROP 2 LAST ROOM RISER1
J 0
(-3825 2375);
DISPLAY 0.829787 (-3825 2375);
PAINT RED (-3825 2375);
DISPLAY INVISIBLE (-3825 2375);
FORCEPROP 2 LAST BOM_COST IO_SLOT
J 0
(-3825 2425);
DISPLAY 0.829787 (-3825 2425);
DISPLAY INVISIBLE (-3825 2425);
FORCEPROP 2 LAST CDS_LIB mstr_standard
J 0
(-3325 2325);
DISPLAY INVISIBLE (-3325 2325);
FORCEPROP 1 LAST BODY_TYPE PLUMBING
J 2
(-3325 2275);
DISPLAY 0.702128 (-3325 2275);
PAINT GREEN (-3325 2275);
DISPLAY INVISIBLE (-3325 2275);
FORCEPROP 1 LAST HDL_TAP TRUE
J 2
(-3650 2200);
DISPLAY 0.702128 (-3650 2200);
PAINT GREEN (-3650 2200);
DISPLAY INVISIBLE (-3650 2200);
FORCEPROP 1 LAST PATH I223
J 2
(-3323 2325);
DISPLAY 0.872340 (-3323 2325);
PAINT GREEN (-3323 2325);
DISPLAY INVISIBLE (-3323 2325);
FORCEADD TAP..6
R 2
(-3325 2125);
FORCEPROP 3 LASTPIN (-3375 2125) SIG_NAME P5E_CPU0_P1_TX_DP<2>
J 0
(-3365 2135);
DISPLAY 0.659574 (-3365 2135);
PAINT MONO (-3365 2135);
DISPLAY INVISIBLE (-3365 2135);
FORCEPROP 1 LASTPIN (-3375 2125) BN 2
J 2
(-3323 2133);
DISPLAY 0.489362 (-3323 2133);
PAINT MONO (-3323 2133);
FORCEPROP 2 LAST ROOM RISER1
J 0
(-3825 2175);
DISPLAY 0.829787 (-3825 2175);
PAINT RED (-3825 2175);
DISPLAY INVISIBLE (-3825 2175);
FORCEPROP 2 LAST BOM_COST IO_SLOT
J 0
(-3825 2225);
DISPLAY 0.829787 (-3825 2225);
DISPLAY INVISIBLE (-3825 2225);
FORCEPROP 2 LAST CDS_LIB standard
J 0
(-3325 2125);
DISPLAY INVISIBLE (-3325 2125);
FORCEPROP 1 LAST BODY_TYPE PLUMBING
J 2
(-3325 2075);
DISPLAY 0.702128 (-3325 2075);
PAINT GREEN (-3325 2075);
DISPLAY INVISIBLE (-3325 2075);
FORCEPROP 1 LAST HDL_TAP TRUE
J 2
(-3650 2000);
DISPLAY 0.702128 (-3650 2000);
PAINT GREEN (-3650 2000);
DISPLAY INVISIBLE (-3650 2000);
FORCEPROP 1 LAST PATH I224
J 2
(-3323 2125);
DISPLAY 0.872340 (-3323 2125);
PAINT GREEN (-3323 2125);
DISPLAY INVISIBLE (-3323 2125);
FORCEADD TAP..6
R 2
(-3175 2075);
FORCEPROP 3 LASTPIN (-3225 2075) SIG_NAME P5E_CPU0_P1_TX_DN<2>
J 0
(-3215 2085);
DISPLAY 0.659574 (-3215 2085);
PAINT MONO (-3215 2085);
DISPLAY INVISIBLE (-3215 2085);
FORCEPROP 1 LASTPIN (-3225 2075) BN 2
J 2
(-3173 2083);
DISPLAY 0.489362 (-3173 2083);
PAINT MONO (-3173 2083);
FORCEPROP 2 LAST ROOM RISER1
J 0
(-3675 2125);
DISPLAY 0.829787 (-3675 2125);
PAINT RED (-3675 2125);
DISPLAY INVISIBLE (-3675 2125);
FORCEPROP 2 LAST BOM_COST IO_SLOT
J 0
(-3675 2175);
DISPLAY 0.829787 (-3675 2175);
DISPLAY INVISIBLE (-3675 2175);
FORCEPROP 2 LAST CDS_LIB standard
J 0
(-3175 2075);
DISPLAY INVISIBLE (-3175 2075);
FORCEPROP 1 LAST BODY_TYPE PLUMBING
J 2
(-3175 2025);
DISPLAY 0.702128 (-3175 2025);
PAINT GREEN (-3175 2025);
DISPLAY INVISIBLE (-3175 2025);
FORCEPROP 1 LAST HDL_TAP TRUE
J 2
(-3500 1950);
DISPLAY 0.702128 (-3500 1950);
PAINT GREEN (-3500 1950);
DISPLAY INVISIBLE (-3500 1950);
FORCEPROP 1 LAST PATH I225
J 2
(-3173 2075);
DISPLAY 0.872340 (-3173 2075);
PAINT GREEN (-3173 2075);
DISPLAY INVISIBLE (-3173 2075);
FORCEADD TAP..6
R 2
(-3175 1875);
FORCEPROP 3 LASTPIN (-3225 1875) SIG_NAME P5E_CPU0_P1_TX_DN<4>
J 0
(-3215 1885);
DISPLAY 0.659574 (-3215 1885);
PAINT MONO (-3215 1885);
DISPLAY INVISIBLE (-3215 1885);
FORCEPROP 1 LASTPIN (-3225 1875) BN 4
J 2
(-3173 1883);
DISPLAY 0.489362 (-3173 1883);
PAINT MONO (-3173 1883);
FORCEPROP 2 LAST ROOM RISER1
J 0
(-3675 1925);
DISPLAY 0.829787 (-3675 1925);
PAINT RED (-3675 1925);
DISPLAY INVISIBLE (-3675 1925);
FORCEPROP 2 LAST BOM_COST IO_SLOT
J 0
(-3675 1975);
DISPLAY 0.829787 (-3675 1975);
DISPLAY INVISIBLE (-3675 1975);
FORCEPROP 2 LAST CDS_LIB standard
J 0
(-3175 1875);
DISPLAY INVISIBLE (-3175 1875);
FORCEPROP 1 LAST BODY_TYPE PLUMBING
J 2
(-3175 1825);
DISPLAY 0.702128 (-3175 1825);
PAINT GREEN (-3175 1825);
DISPLAY INVISIBLE (-3175 1825);
FORCEPROP 1 LAST HDL_TAP TRUE
J 2
(-3500 1750);
DISPLAY 0.702128 (-3500 1750);
PAINT GREEN (-3500 1750);
DISPLAY INVISIBLE (-3500 1750);
FORCEPROP 1 LAST PATH I226
J 2
(-3173 1875);
DISPLAY 0.872340 (-3173 1875);
PAINT GREEN (-3173 1875);
DISPLAY INVISIBLE (-3173 1875);
FORCEADD TAP..6
R 2
(-3175 1975);
FORCEPROP 3 LASTPIN (-3225 1975) SIG_NAME P5E_CPU0_P1_TX_DN<3>
J 0
(-3215 1985);
DISPLAY 0.659574 (-3215 1985);
PAINT MONO (-3215 1985);
DISPLAY INVISIBLE (-3215 1985);
FORCEPROP 1 LASTPIN (-3225 1975) BN 3
J 2
(-3173 1983);
DISPLAY 0.489362 (-3173 1983);
PAINT MONO (-3173 1983);
FORCEPROP 2 LAST ROOM RISER1
J 0
(-3675 2025);
DISPLAY 0.829787 (-3675 2025);
PAINT RED (-3675 2025);
DISPLAY INVISIBLE (-3675 2025);
FORCEPROP 2 LAST BOM_COST IO_SLOT
J 0
(-3675 2075);
DISPLAY 0.829787 (-3675 2075);
DISPLAY INVISIBLE (-3675 2075);
FORCEPROP 2 LAST CDS_LIB standard
J 0
(-3175 1975);
DISPLAY INVISIBLE (-3175 1975);
FORCEPROP 1 LAST BODY_TYPE PLUMBING
J 2
(-3175 1925);
DISPLAY 0.702128 (-3175 1925);
PAINT GREEN (-3175 1925);
DISPLAY INVISIBLE (-3175 1925);
FORCEPROP 1 LAST HDL_TAP TRUE
J 2
(-3500 1850);
DISPLAY 0.702128 (-3500 1850);
PAINT GREEN (-3500 1850);
DISPLAY INVISIBLE (-3500 1850);
FORCEPROP 1 LAST PATH I227
J 2
(-3173 1975);
DISPLAY 0.872340 (-3173 1975);
PAINT GREEN (-3173 1975);
DISPLAY INVISIBLE (-3173 1975);
FORCEADD TAP..6
R 2
(-3325 2025);
FORCEPROP 3 LASTPIN (-3375 2025) SIG_NAME P5E_CPU0_P1_TX_DP<3>
J 0
(-3365 2035);
DISPLAY 0.659574 (-3365 2035);
PAINT MONO (-3365 2035);
DISPLAY INVISIBLE (-3365 2035);
FORCEPROP 1 LASTPIN (-3375 2025) BN 3
J 2
(-3323 2033);
DISPLAY 0.489362 (-3323 2033);
PAINT MONO (-3323 2033);
FORCEPROP 2 LAST ROOM RISER1
J 0
(-3825 2075);
DISPLAY 0.829787 (-3825 2075);
PAINT RED (-3825 2075);
DISPLAY INVISIBLE (-3825 2075);
FORCEPROP 2 LAST BOM_COST IO_SLOT
J 0
(-3825 2125);
DISPLAY 0.829787 (-3825 2125);
DISPLAY INVISIBLE (-3825 2125);
FORCEPROP 2 LAST CDS_LIB standard
J 0
(-3325 2025);
DISPLAY INVISIBLE (-3325 2025);
FORCEPROP 1 LAST BODY_TYPE PLUMBING
J 2
(-3325 1975);
DISPLAY 0.702128 (-3325 1975);
PAINT GREEN (-3325 1975);
DISPLAY INVISIBLE (-3325 1975);
FORCEPROP 1 LAST HDL_TAP TRUE
J 2
(-3650 1900);
DISPLAY 0.702128 (-3650 1900);
PAINT GREEN (-3650 1900);
DISPLAY INVISIBLE (-3650 1900);
FORCEPROP 1 LAST PATH I228
J 2
(-3323 2025);
DISPLAY 0.872340 (-3323 2025);
PAINT GREEN (-3323 2025);
DISPLAY INVISIBLE (-3323 2025);
FORCEADD TAP..6
R 2
(-3325 1925);
FORCEPROP 3 LASTPIN (-3375 1925) SIG_NAME P5E_CPU0_P1_TX_DP<4>
J 0
(-3365 1935);
DISPLAY 0.659574 (-3365 1935);
PAINT MONO (-3365 1935);
DISPLAY INVISIBLE (-3365 1935);
FORCEPROP 1 LASTPIN (-3375 1925) BN 4
J 2
(-3323 1933);
DISPLAY 0.489362 (-3323 1933);
PAINT MONO (-3323 1933);
FORCEPROP 2 LAST ROOM RISER1
J 0
(-3825 1975);
DISPLAY 0.829787 (-3825 1975);
PAINT RED (-3825 1975);
DISPLAY INVISIBLE (-3825 1975);
FORCEPROP 2 LAST BOM_COST IO_SLOT
J 0
(-3825 2025);
DISPLAY 0.829787 (-3825 2025);
DISPLAY INVISIBLE (-3825 2025);
FORCEPROP 2 LAST CDS_LIB standard
J 0
(-3325 1925);
DISPLAY INVISIBLE (-3325 1925);
FORCEPROP 1 LAST BODY_TYPE PLUMBING
J 2
(-3325 1875);
DISPLAY 0.702128 (-3325 1875);
PAINT GREEN (-3325 1875);
DISPLAY INVISIBLE (-3325 1875);
FORCEPROP 1 LAST HDL_TAP TRUE
J 2
(-3650 1800);
DISPLAY 0.702128 (-3650 1800);
PAINT GREEN (-3650 1800);
DISPLAY INVISIBLE (-3650 1800);
FORCEPROP 1 LAST PATH I229
J 2
(-3323 1925);
DISPLAY 0.872340 (-3323 1925);
PAINT GREEN (-3323 1925);
DISPLAY INVISIBLE (-3323 1925);
FORCEADD TAP..6
R 2
(-3175 1775);
FORCEPROP 3 LASTPIN (-3225 1775) SIG_NAME P5E_CPU0_P1_TX_DN<5>
J 0
(-3215 1785);
DISPLAY 0.659574 (-3215 1785);
PAINT MONO (-3215 1785);
DISPLAY INVISIBLE (-3215 1785);
FORCEPROP 1 LASTPIN (-3225 1775) BN 5
J 2
(-3173 1783);
DISPLAY 0.489362 (-3173 1783);
PAINT MONO (-3173 1783);
FORCEPROP 2 LAST ROOM RISER1
J 0
(-3675 1825);
DISPLAY 0.829787 (-3675 1825);
PAINT RED (-3675 1825);
DISPLAY INVISIBLE (-3675 1825);
FORCEPROP 2 LAST BOM_COST IO_SLOT
J 0
(-3675 1875);
DISPLAY 0.829787 (-3675 1875);
DISPLAY INVISIBLE (-3675 1875);
FORCEPROP 2 LAST CDS_LIB standard
J 0
(-3175 1775);
DISPLAY INVISIBLE (-3175 1775);
FORCEPROP 1 LAST BODY_TYPE PLUMBING
J 2
(-3175 1725);
DISPLAY 0.702128 (-3175 1725);
PAINT GREEN (-3175 1725);
DISPLAY INVISIBLE (-3175 1725);
FORCEPROP 1 LAST HDL_TAP TRUE
J 2
(-3500 1650);
DISPLAY 0.702128 (-3500 1650);
PAINT GREEN (-3500 1650);
DISPLAY INVISIBLE (-3500 1650);
FORCEPROP 1 LAST PATH I230
J 2
(-3173 1775);
DISPLAY 0.872340 (-3173 1775);
PAINT GREEN (-3173 1775);
DISPLAY INVISIBLE (-3173 1775);
FORCEADD TAP..6
R 2
(-3175 1675);
FORCEPROP 3 LASTPIN (-3225 1675) SIG_NAME P5E_CPU0_P1_TX_DN<6>
J 0
(-3215 1685);
DISPLAY 0.659574 (-3215 1685);
PAINT MONO (-3215 1685);
DISPLAY INVISIBLE (-3215 1685);
FORCEPROP 1 LASTPIN (-3225 1675) BN 6
J 2
(-3173 1683);
DISPLAY 0.489362 (-3173 1683);
PAINT MONO (-3173 1683);
FORCEPROP 2 LAST ROOM RISER1
J 0
(-3675 1725);
DISPLAY 0.829787 (-3675 1725);
PAINT RED (-3675 1725);
DISPLAY INVISIBLE (-3675 1725);
FORCEPROP 2 LAST BOM_COST IO_SLOT
J 0
(-3675 1775);
DISPLAY 0.829787 (-3675 1775);
DISPLAY INVISIBLE (-3675 1775);
FORCEPROP 2 LAST CDS_LIB standard
J 0
(-3175 1675);
DISPLAY INVISIBLE (-3175 1675);
FORCEPROP 1 LAST BODY_TYPE PLUMBING
J 2
(-3175 1625);
DISPLAY 0.702128 (-3175 1625);
PAINT GREEN (-3175 1625);
DISPLAY INVISIBLE (-3175 1625);
FORCEPROP 1 LAST HDL_TAP TRUE
J 2
(-3500 1550);
DISPLAY 0.702128 (-3500 1550);
PAINT GREEN (-3500 1550);
DISPLAY INVISIBLE (-3500 1550);
FORCEPROP 1 LAST PATH I231
J 2
(-3173 1675);
DISPLAY 0.872340 (-3173 1675);
PAINT GREEN (-3173 1675);
DISPLAY INVISIBLE (-3173 1675);
FORCEADD TAP..6
R 2
(-3325 1725);
FORCEPROP 3 LASTPIN (-3375 1725) SIG_NAME P5E_CPU0_P1_TX_DP<6>
J 0
(-3365 1735);
DISPLAY 0.659574 (-3365 1735);
PAINT MONO (-3365 1735);
DISPLAY INVISIBLE (-3365 1735);
FORCEPROP 1 LASTPIN (-3375 1725) BN 6
J 2
(-3323 1733);
DISPLAY 0.489362 (-3323 1733);
PAINT MONO (-3323 1733);
FORCEPROP 2 LAST ROOM RISER1
J 0
(-3825 1775);
DISPLAY 0.829787 (-3825 1775);
PAINT RED (-3825 1775);
DISPLAY INVISIBLE (-3825 1775);
FORCEPROP 2 LAST BOM_COST IO_SLOT
J 0
(-3825 1825);
DISPLAY 0.829787 (-3825 1825);
DISPLAY INVISIBLE (-3825 1825);
FORCEPROP 2 LAST CDS_LIB standard
J 0
(-3325 1725);
DISPLAY INVISIBLE (-3325 1725);
FORCEPROP 1 LAST BODY_TYPE PLUMBING
J 2
(-3325 1675);
DISPLAY 0.702128 (-3325 1675);
PAINT GREEN (-3325 1675);
DISPLAY INVISIBLE (-3325 1675);
FORCEPROP 1 LAST HDL_TAP TRUE
J 2
(-3650 1600);
DISPLAY 0.702128 (-3650 1600);
PAINT GREEN (-3650 1600);
DISPLAY INVISIBLE (-3650 1600);
FORCEPROP 1 LAST PATH I232
J 2
(-3323 1725);
DISPLAY 0.872340 (-3323 1725);
PAINT GREEN (-3323 1725);
DISPLAY INVISIBLE (-3323 1725);
FORCEADD TAP..6
R 2
(-3325 1825);
FORCEPROP 3 LASTPIN (-3375 1825) SIG_NAME P5E_CPU0_P1_TX_DP<5>
J 0
(-3365 1835);
DISPLAY 0.659574 (-3365 1835);
PAINT MONO (-3365 1835);
DISPLAY INVISIBLE (-3365 1835);
FORCEPROP 1 LASTPIN (-3375 1825) BN 5
J 2
(-3323 1833);
DISPLAY 0.489362 (-3323 1833);
PAINT MONO (-3323 1833);
FORCEPROP 2 LAST ROOM RISER1
J 0
(-3825 1875);
DISPLAY 0.829787 (-3825 1875);
PAINT RED (-3825 1875);
DISPLAY INVISIBLE (-3825 1875);
FORCEPROP 2 LAST BOM_COST IO_SLOT
J 0
(-3825 1925);
DISPLAY 0.829787 (-3825 1925);
DISPLAY INVISIBLE (-3825 1925);
FORCEPROP 2 LAST CDS_LIB standard
J 0
(-3325 1825);
DISPLAY INVISIBLE (-3325 1825);
FORCEPROP 1 LAST BODY_TYPE PLUMBING
J 2
(-3325 1775);
DISPLAY 0.702128 (-3325 1775);
PAINT GREEN (-3325 1775);
DISPLAY INVISIBLE (-3325 1775);
FORCEPROP 1 LAST HDL_TAP TRUE
J 2
(-3650 1700);
DISPLAY 0.702128 (-3650 1700);
PAINT GREEN (-3650 1700);
DISPLAY INVISIBLE (-3650 1700);
FORCEPROP 1 LAST PATH I233
J 2
(-3323 1825);
DISPLAY 0.872340 (-3323 1825);
PAINT GREEN (-3323 1825);
DISPLAY INVISIBLE (-3323 1825);
FORCEADD TAP..6
R 2
(-3325 1625);
FORCEPROP 3 LASTPIN (-3375 1625) SIG_NAME P5E_CPU0_P1_TX_DP<7>
J 0
(-3365 1635);
DISPLAY 0.659574 (-3365 1635);
PAINT MONO (-3365 1635);
DISPLAY INVISIBLE (-3365 1635);
FORCEPROP 1 LASTPIN (-3375 1625) BN 7
J 2
(-3323 1633);
DISPLAY 0.489362 (-3323 1633);
PAINT MONO (-3323 1633);
FORCEPROP 2 LAST ROOM RISER1
J 0
(-3825 1675);
DISPLAY 0.829787 (-3825 1675);
PAINT RED (-3825 1675);
DISPLAY INVISIBLE (-3825 1675);
FORCEPROP 2 LAST BOM_COST IO_SLOT
J 0
(-3825 1725);
DISPLAY 0.829787 (-3825 1725);
DISPLAY INVISIBLE (-3825 1725);
FORCEPROP 2 LAST CDS_LIB standard
J 0
(-3325 1625);
DISPLAY INVISIBLE (-3325 1625);
FORCEPROP 1 LAST BODY_TYPE PLUMBING
J 2
(-3325 1575);
DISPLAY 0.702128 (-3325 1575);
PAINT GREEN (-3325 1575);
DISPLAY INVISIBLE (-3325 1575);
FORCEPROP 1 LAST HDL_TAP TRUE
J 2
(-3650 1500);
DISPLAY 0.702128 (-3650 1500);
PAINT GREEN (-3650 1500);
DISPLAY INVISIBLE (-3650 1500);
FORCEPROP 1 LAST PATH I234
J 2
(-3323 1625);
DISPLAY 0.872340 (-3323 1625);
PAINT GREEN (-3323 1625);
DISPLAY INVISIBLE (-3323 1625);
FORCEADD TAP..6
R 2
(-3175 1575);
FORCEPROP 3 LASTPIN (-3225 1575) SIG_NAME P5E_CPU0_P1_TX_DN<7>
J 0
(-3215 1585);
DISPLAY 0.659574 (-3215 1585);
PAINT MONO (-3215 1585);
DISPLAY INVISIBLE (-3215 1585);
FORCEPROP 1 LASTPIN (-3225 1575) BN 7
J 2
(-3173 1583);
DISPLAY 0.489362 (-3173 1583);
PAINT MONO (-3173 1583);
FORCEPROP 2 LAST ROOM RISER1
J 0
(-3675 1625);
DISPLAY 0.829787 (-3675 1625);
PAINT RED (-3675 1625);
DISPLAY INVISIBLE (-3675 1625);
FORCEPROP 2 LAST BOM_COST IO_SLOT
J 0
(-3675 1675);
DISPLAY 0.829787 (-3675 1675);
DISPLAY INVISIBLE (-3675 1675);
FORCEPROP 2 LAST CDS_LIB standard
J 0
(-3175 1575);
DISPLAY INVISIBLE (-3175 1575);
FORCEPROP 1 LAST BODY_TYPE PLUMBING
J 2
(-3175 1525);
DISPLAY 0.702128 (-3175 1525);
PAINT GREEN (-3175 1525);
DISPLAY INVISIBLE (-3175 1525);
FORCEPROP 1 LAST HDL_TAP TRUE
J 2
(-3500 1450);
DISPLAY 0.702128 (-3500 1450);
PAINT GREEN (-3500 1450);
DISPLAY INVISIBLE (-3500 1450);
FORCEPROP 1 LAST PATH I235
J 2
(-3173 1575);
DISPLAY 0.872340 (-3173 1575);
PAINT GREEN (-3173 1575);
DISPLAY INVISIBLE (-3173 1575);
FORCEADD TAP..6
R 2
(-3175 1375);
FORCEPROP 3 LASTPIN (-3225 1375) SIG_NAME P5E_CPU0_P1_TX_DN<9>
J 0
(-3215 1385);
DISPLAY 0.659574 (-3215 1385);
PAINT MONO (-3215 1385);
DISPLAY INVISIBLE (-3215 1385);
FORCEPROP 1 LASTPIN (-3225 1375) BN 9
J 2
(-3173 1383);
DISPLAY 0.489362 (-3173 1383);
PAINT MONO (-3173 1383);
FORCEPROP 2 LAST ROOM RISER1
J 0
(-3675 1425);
DISPLAY 0.829787 (-3675 1425);
PAINT RED (-3675 1425);
DISPLAY INVISIBLE (-3675 1425);
FORCEPROP 2 LAST BOM_COST IO_SLOT
J 0
(-3675 1475);
DISPLAY 0.829787 (-3675 1475);
DISPLAY INVISIBLE (-3675 1475);
FORCEPROP 2 LAST CDS_LIB standard
J 0
(-3175 1375);
DISPLAY INVISIBLE (-3175 1375);
FORCEPROP 1 LAST BODY_TYPE PLUMBING
J 2
(-3175 1325);
DISPLAY 0.702128 (-3175 1325);
PAINT GREEN (-3175 1325);
DISPLAY INVISIBLE (-3175 1325);
FORCEPROP 1 LAST HDL_TAP TRUE
J 2
(-3500 1250);
DISPLAY 0.702128 (-3500 1250);
PAINT GREEN (-3500 1250);
DISPLAY INVISIBLE (-3500 1250);
FORCEPROP 1 LAST PATH I236
J 2
(-3173 1375);
DISPLAY 0.872340 (-3173 1375);
PAINT GREEN (-3173 1375);
DISPLAY INVISIBLE (-3173 1375);
FORCEADD TAP..6
R 2
(-3175 1475);
FORCEPROP 3 LASTPIN (-3225 1475) SIG_NAME P5E_CPU0_P1_TX_DN<8>
J 0
(-3215 1485);
DISPLAY 0.659574 (-3215 1485);
PAINT MONO (-3215 1485);
DISPLAY INVISIBLE (-3215 1485);
FORCEPROP 1 LASTPIN (-3225 1475) BN 8
J 2
(-3173 1483);
DISPLAY 0.489362 (-3173 1483);
PAINT MONO (-3173 1483);
FORCEPROP 2 LAST ROOM RISER1
J 0
(-3675 1525);
DISPLAY 0.829787 (-3675 1525);
PAINT RED (-3675 1525);
DISPLAY INVISIBLE (-3675 1525);
FORCEPROP 2 LAST BOM_COST IO_SLOT
J 0
(-3675 1575);
DISPLAY 0.829787 (-3675 1575);
DISPLAY INVISIBLE (-3675 1575);
FORCEPROP 2 LAST CDS_LIB standard
J 0
(-3175 1475);
DISPLAY INVISIBLE (-3175 1475);
FORCEPROP 1 LAST BODY_TYPE PLUMBING
J 2
(-3175 1425);
DISPLAY 0.702128 (-3175 1425);
PAINT GREEN (-3175 1425);
DISPLAY INVISIBLE (-3175 1425);
FORCEPROP 1 LAST HDL_TAP TRUE
J 2
(-3500 1350);
DISPLAY 0.702128 (-3500 1350);
PAINT GREEN (-3500 1350);
DISPLAY INVISIBLE (-3500 1350);
FORCEPROP 1 LAST PATH I237
J 2
(-3173 1475);
DISPLAY 0.872340 (-3173 1475);
PAINT GREEN (-3173 1475);
DISPLAY INVISIBLE (-3173 1475);
FORCEADD TAP..6
R 2
(-3325 1525);
FORCEPROP 3 LASTPIN (-3375 1525) SIG_NAME P5E_CPU0_P1_TX_DP<8>
J 0
(-3365 1535);
DISPLAY 0.659574 (-3365 1535);
PAINT MONO (-3365 1535);
DISPLAY INVISIBLE (-3365 1535);
FORCEPROP 1 LASTPIN (-3375 1525) BN 8
J 2
(-3323 1533);
DISPLAY 0.489362 (-3323 1533);
PAINT MONO (-3323 1533);
FORCEPROP 2 LAST ROOM RISER1
J 0
(-3825 1575);
DISPLAY 0.829787 (-3825 1575);
PAINT RED (-3825 1575);
DISPLAY INVISIBLE (-3825 1575);
FORCEPROP 2 LAST BOM_COST IO_SLOT
J 0
(-3825 1625);
DISPLAY 0.829787 (-3825 1625);
DISPLAY INVISIBLE (-3825 1625);
FORCEPROP 2 LAST CDS_LIB standard
J 0
(-3325 1525);
DISPLAY INVISIBLE (-3325 1525);
FORCEPROP 1 LAST BODY_TYPE PLUMBING
J 2
(-3325 1475);
DISPLAY 0.702128 (-3325 1475);
PAINT GREEN (-3325 1475);
DISPLAY INVISIBLE (-3325 1475);
FORCEPROP 1 LAST HDL_TAP TRUE
J 2
(-3650 1400);
DISPLAY 0.702128 (-3650 1400);
PAINT GREEN (-3650 1400);
DISPLAY INVISIBLE (-3650 1400);
FORCEPROP 1 LAST PATH I238
J 2
(-3323 1525);
DISPLAY 0.872340 (-3323 1525);
PAINT GREEN (-3323 1525);
DISPLAY INVISIBLE (-3323 1525);
FORCEADD TAP..6
R 2
(-3325 1425);
FORCEPROP 3 LASTPIN (-3375 1425) SIG_NAME P5E_CPU0_P1_TX_DP<9>
J 0
(-3365 1435);
DISPLAY 0.659574 (-3365 1435);
PAINT MONO (-3365 1435);
DISPLAY INVISIBLE (-3365 1435);
FORCEPROP 1 LASTPIN (-3375 1425) BN 9
J 2
(-3323 1433);
DISPLAY 0.489362 (-3323 1433);
PAINT MONO (-3323 1433);
FORCEPROP 2 LAST ROOM RISER1
J 0
(-3825 1475);
DISPLAY 0.829787 (-3825 1475);
PAINT RED (-3825 1475);
DISPLAY INVISIBLE (-3825 1475);
FORCEPROP 2 LAST BOM_COST IO_SLOT
J 0
(-3825 1525);
DISPLAY 0.829787 (-3825 1525);
DISPLAY INVISIBLE (-3825 1525);
FORCEPROP 2 LAST CDS_LIB standard
J 0
(-3325 1425);
DISPLAY INVISIBLE (-3325 1425);
FORCEPROP 1 LAST BODY_TYPE PLUMBING
J 2
(-3325 1375);
DISPLAY 0.702128 (-3325 1375);
PAINT GREEN (-3325 1375);
DISPLAY INVISIBLE (-3325 1375);
FORCEPROP 1 LAST HDL_TAP TRUE
J 2
(-3650 1300);
DISPLAY 0.702128 (-3650 1300);
PAINT GREEN (-3650 1300);
DISPLAY INVISIBLE (-3650 1300);
FORCEPROP 1 LAST PATH I239
J 2
(-3323 1425);
DISPLAY 0.872340 (-3323 1425);
PAINT GREEN (-3323 1425);
DISPLAY INVISIBLE (-3323 1425);
FORCEADD TAP..6
R 2
(-3175 1275);
FORCEPROP 3 LASTPIN (-3225 1275) SIG_NAME P5E_CPU0_P1_TX_DN<10>
J 0
(-3215 1285);
DISPLAY 0.659574 (-3215 1285);
PAINT MONO (-3215 1285);
DISPLAY INVISIBLE (-3215 1285);
FORCEPROP 1 LASTPIN (-3225 1275) BN 10
J 2
(-3173 1283);
DISPLAY 0.489362 (-3173 1283);
PAINT MONO (-3173 1283);
FORCEPROP 2 LAST ROOM RISER1
J 0
(-3675 1325);
DISPLAY 0.829787 (-3675 1325);
PAINT RED (-3675 1325);
DISPLAY INVISIBLE (-3675 1325);
FORCEPROP 2 LAST BOM_COST IO_SLOT
J 0
(-3675 1375);
DISPLAY 0.829787 (-3675 1375);
DISPLAY INVISIBLE (-3675 1375);
FORCEPROP 2 LAST CDS_LIB standard
J 0
(-3175 1275);
DISPLAY INVISIBLE (-3175 1275);
FORCEPROP 1 LAST BODY_TYPE PLUMBING
J 2
(-3175 1225);
DISPLAY 0.702128 (-3175 1225);
PAINT GREEN (-3175 1225);
DISPLAY INVISIBLE (-3175 1225);
FORCEPROP 1 LAST HDL_TAP TRUE
J 2
(-3500 1150);
DISPLAY 0.702128 (-3500 1150);
PAINT GREEN (-3500 1150);
DISPLAY INVISIBLE (-3500 1150);
FORCEPROP 1 LAST PATH I240
J 2
(-3173 1275);
DISPLAY 0.872340 (-3173 1275);
PAINT GREEN (-3173 1275);
DISPLAY INVISIBLE (-3173 1275);
FORCEADD TAP..6
R 2
(-3175 1175);
FORCEPROP 3 LASTPIN (-3225 1175) SIG_NAME P5E_CPU0_P1_TX_DN<11>
J 0
(-3215 1185);
DISPLAY 0.659574 (-3215 1185);
PAINT MONO (-3215 1185);
DISPLAY INVISIBLE (-3215 1185);
FORCEPROP 1 LASTPIN (-3225 1175) BN 11
J 2
(-3173 1183);
DISPLAY 0.489362 (-3173 1183);
PAINT MONO (-3173 1183);
FORCEPROP 2 LAST ROOM RISER1
J 0
(-3675 1225);
DISPLAY 0.829787 (-3675 1225);
PAINT RED (-3675 1225);
DISPLAY INVISIBLE (-3675 1225);
FORCEPROP 2 LAST BOM_COST IO_SLOT
J 0
(-3675 1275);
DISPLAY 0.829787 (-3675 1275);
DISPLAY INVISIBLE (-3675 1275);
FORCEPROP 2 LAST CDS_LIB standard
J 0
(-3175 1175);
DISPLAY INVISIBLE (-3175 1175);
FORCEPROP 1 LAST BODY_TYPE PLUMBING
J 2
(-3175 1125);
DISPLAY 0.702128 (-3175 1125);
PAINT GREEN (-3175 1125);
DISPLAY INVISIBLE (-3175 1125);
FORCEPROP 1 LAST HDL_TAP TRUE
J 2
(-3500 1050);
DISPLAY 0.702128 (-3500 1050);
PAINT GREEN (-3500 1050);
DISPLAY INVISIBLE (-3500 1050);
FORCEPROP 1 LAST PATH I241
J 2
(-3173 1175);
DISPLAY 0.872340 (-3173 1175);
PAINT GREEN (-3173 1175);
DISPLAY INVISIBLE (-3173 1175);
FORCEADD TAP..6
R 2
(-3325 1125);
FORCEPROP 3 LASTPIN (-3375 1125) SIG_NAME P5E_CPU0_P1_TX_DP<12>
J 0
(-3365 1135);
DISPLAY 0.659574 (-3365 1135);
PAINT MONO (-3365 1135);
DISPLAY INVISIBLE (-3365 1135);
FORCEPROP 1 LASTPIN (-3375 1125) BN 12
J 2
(-3323 1133);
DISPLAY 0.489362 (-3323 1133);
PAINT MONO (-3323 1133);
FORCEPROP 2 LAST ROOM RISER1
J 0
(-3825 1175);
DISPLAY 0.829787 (-3825 1175);
PAINT RED (-3825 1175);
DISPLAY INVISIBLE (-3825 1175);
FORCEPROP 2 LAST BOM_COST IO_SLOT
J 0
(-3825 1225);
DISPLAY 0.829787 (-3825 1225);
DISPLAY INVISIBLE (-3825 1225);
FORCEPROP 2 LAST CDS_LIB standard
J 0
(-3325 1125);
DISPLAY INVISIBLE (-3325 1125);
FORCEPROP 1 LAST BODY_TYPE PLUMBING
J 2
(-3325 1075);
DISPLAY 0.702128 (-3325 1075);
PAINT GREEN (-3325 1075);
DISPLAY INVISIBLE (-3325 1075);
FORCEPROP 1 LAST HDL_TAP TRUE
J 2
(-3650 1000);
DISPLAY 0.702128 (-3650 1000);
PAINT GREEN (-3650 1000);
DISPLAY INVISIBLE (-3650 1000);
FORCEPROP 1 LAST PATH I242
J 2
(-3323 1125);
DISPLAY 0.872340 (-3323 1125);
PAINT GREEN (-3323 1125);
DISPLAY INVISIBLE (-3323 1125);
FORCEADD TAP..6
R 2
(-3325 1225);
FORCEPROP 3 LASTPIN (-3375 1225) SIG_NAME P5E_CPU0_P1_TX_DP<11>
J 0
(-3365 1235);
DISPLAY 0.659574 (-3365 1235);
PAINT MONO (-3365 1235);
DISPLAY INVISIBLE (-3365 1235);
FORCEPROP 1 LASTPIN (-3375 1225) BN 11
J 2
(-3323 1233);
DISPLAY 0.489362 (-3323 1233);
PAINT MONO (-3323 1233);
FORCEPROP 2 LAST ROOM RISER1
J 0
(-3825 1275);
DISPLAY 0.829787 (-3825 1275);
PAINT RED (-3825 1275);
DISPLAY INVISIBLE (-3825 1275);
FORCEPROP 2 LAST BOM_COST IO_SLOT
J 0
(-3825 1325);
DISPLAY 0.829787 (-3825 1325);
DISPLAY INVISIBLE (-3825 1325);
FORCEPROP 2 LAST CDS_LIB standard
J 0
(-3325 1225);
DISPLAY INVISIBLE (-3325 1225);
FORCEPROP 1 LAST BODY_TYPE PLUMBING
J 2
(-3325 1175);
DISPLAY 0.702128 (-3325 1175);
PAINT GREEN (-3325 1175);
DISPLAY INVISIBLE (-3325 1175);
FORCEPROP 1 LAST HDL_TAP TRUE
J 2
(-3650 1100);
DISPLAY 0.702128 (-3650 1100);
PAINT GREEN (-3650 1100);
DISPLAY INVISIBLE (-3650 1100);
FORCEPROP 1 LAST PATH I243
J 2
(-3323 1225);
DISPLAY 0.872340 (-3323 1225);
PAINT GREEN (-3323 1225);
DISPLAY INVISIBLE (-3323 1225);
FORCEADD TAP..6
R 2
(-3325 1325);
FORCEPROP 3 LASTPIN (-3375 1325) SIG_NAME P5E_CPU0_P1_TX_DP<10>
J 0
(-3365 1335);
DISPLAY 0.659574 (-3365 1335);
PAINT MONO (-3365 1335);
DISPLAY INVISIBLE (-3365 1335);
FORCEPROP 1 LASTPIN (-3375 1325) BN 10
J 2
(-3323 1333);
DISPLAY 0.489362 (-3323 1333);
PAINT MONO (-3323 1333);
FORCEPROP 2 LAST ROOM RISER1
J 0
(-3825 1375);
DISPLAY 0.829787 (-3825 1375);
PAINT RED (-3825 1375);
DISPLAY INVISIBLE (-3825 1375);
FORCEPROP 2 LAST BOM_COST IO_SLOT
J 0
(-3825 1425);
DISPLAY 0.829787 (-3825 1425);
DISPLAY INVISIBLE (-3825 1425);
FORCEPROP 2 LAST CDS_LIB standard
J 0
(-3325 1325);
DISPLAY INVISIBLE (-3325 1325);
FORCEPROP 1 LAST BODY_TYPE PLUMBING
J 2
(-3325 1275);
DISPLAY 0.702128 (-3325 1275);
PAINT GREEN (-3325 1275);
DISPLAY INVISIBLE (-3325 1275);
FORCEPROP 1 LAST HDL_TAP TRUE
J 2
(-3650 1200);
DISPLAY 0.702128 (-3650 1200);
PAINT GREEN (-3650 1200);
DISPLAY INVISIBLE (-3650 1200);
FORCEPROP 1 LAST PATH I244
J 2
(-3323 1325);
DISPLAY 0.872340 (-3323 1325);
PAINT GREEN (-3323 1325);
DISPLAY INVISIBLE (-3323 1325);
FORCEADD TAP..6
R 2
(-3175 975);
FORCEPROP 3 LASTPIN (-3225 975) SIG_NAME P5E_CPU0_P1_TX_DN<13>
J 0
(-3215 985);
DISPLAY 0.659574 (-3215 985);
PAINT MONO (-3215 985);
DISPLAY INVISIBLE (-3215 985);
FORCEPROP 1 LASTPIN (-3225 975) BN 13
J 2
(-3173 983);
DISPLAY 0.489362 (-3173 983);
PAINT MONO (-3173 983);
FORCEPROP 2 LAST ROOM RISER1
J 0
(-3675 1025);
DISPLAY 0.829787 (-3675 1025);
PAINT RED (-3675 1025);
DISPLAY INVISIBLE (-3675 1025);
FORCEPROP 2 LAST BOM_COST IO_SLOT
J 0
(-3675 1075);
DISPLAY 0.829787 (-3675 1075);
DISPLAY INVISIBLE (-3675 1075);
FORCEPROP 2 LAST CDS_LIB standard
J 0
(-3175 975);
DISPLAY INVISIBLE (-3175 975);
FORCEPROP 1 LAST BODY_TYPE PLUMBING
J 2
(-3175 925);
DISPLAY 0.702128 (-3175 925);
PAINT GREEN (-3175 925);
DISPLAY INVISIBLE (-3175 925);
FORCEPROP 1 LAST HDL_TAP TRUE
J 2
(-3500 850);
DISPLAY 0.702128 (-3500 850);
PAINT GREEN (-3500 850);
DISPLAY INVISIBLE (-3500 850);
FORCEPROP 1 LAST PATH I245
J 2
(-3173 975);
DISPLAY 0.872340 (-3173 975);
PAINT GREEN (-3173 975);
DISPLAY INVISIBLE (-3173 975);
FORCEADD TAP..6
R 2
(-3175 1075);
FORCEPROP 3 LASTPIN (-3225 1075) SIG_NAME P5E_CPU0_P1_TX_DN<12>
J 0
(-3215 1085);
DISPLAY 0.659574 (-3215 1085);
PAINT MONO (-3215 1085);
DISPLAY INVISIBLE (-3215 1085);
FORCEPROP 1 LASTPIN (-3225 1075) BN 12
J 2
(-3173 1083);
DISPLAY 0.489362 (-3173 1083);
PAINT MONO (-3173 1083);
FORCEPROP 2 LAST ROOM RISER1
J 0
(-3675 1125);
DISPLAY 0.829787 (-3675 1125);
PAINT RED (-3675 1125);
DISPLAY INVISIBLE (-3675 1125);
FORCEPROP 2 LAST BOM_COST IO_SLOT
J 0
(-3675 1175);
DISPLAY 0.829787 (-3675 1175);
DISPLAY INVISIBLE (-3675 1175);
FORCEPROP 2 LAST CDS_LIB standard
J 0
(-3175 1075);
DISPLAY INVISIBLE (-3175 1075);
FORCEPROP 1 LAST BODY_TYPE PLUMBING
J 2
(-3175 1025);
DISPLAY 0.702128 (-3175 1025);
PAINT GREEN (-3175 1025);
DISPLAY INVISIBLE (-3175 1025);
FORCEPROP 1 LAST HDL_TAP TRUE
J 2
(-3500 950);
DISPLAY 0.702128 (-3500 950);
PAINT GREEN (-3500 950);
DISPLAY INVISIBLE (-3500 950);
FORCEPROP 1 LAST PATH I246
J 2
(-3173 1075);
DISPLAY 0.872340 (-3173 1075);
PAINT GREEN (-3173 1075);
DISPLAY INVISIBLE (-3173 1075);
FORCEADD TAP..6
R 2
(-3175 875);
FORCEPROP 3 LASTPIN (-3225 875) SIG_NAME P5E_CPU0_P1_TX_DN<14>
J 0
(-3215 885);
DISPLAY 0.659574 (-3215 885);
PAINT MONO (-3215 885);
DISPLAY INVISIBLE (-3215 885);
FORCEPROP 1 LASTPIN (-3225 875) BN 14
J 2
(-3173 883);
DISPLAY 0.489362 (-3173 883);
PAINT MONO (-3173 883);
FORCEPROP 2 LAST ROOM RISER1
J 0
(-3675 925);
DISPLAY 0.829787 (-3675 925);
PAINT RED (-3675 925);
DISPLAY INVISIBLE (-3675 925);
FORCEPROP 2 LAST BOM_COST IO_SLOT
J 0
(-3675 975);
DISPLAY 0.829787 (-3675 975);
DISPLAY INVISIBLE (-3675 975);
FORCEPROP 2 LAST CDS_LIB standard
J 0
(-3175 875);
DISPLAY INVISIBLE (-3175 875);
FORCEPROP 1 LAST BODY_TYPE PLUMBING
J 2
(-3175 825);
DISPLAY 0.702128 (-3175 825);
PAINT GREEN (-3175 825);
DISPLAY INVISIBLE (-3175 825);
FORCEPROP 1 LAST HDL_TAP TRUE
J 2
(-3500 750);
DISPLAY 0.702128 (-3500 750);
PAINT GREEN (-3500 750);
DISPLAY INVISIBLE (-3500 750);
FORCEPROP 1 LAST PATH I247
J 2
(-3173 875);
DISPLAY 0.872340 (-3173 875);
PAINT GREEN (-3173 875);
DISPLAY INVISIBLE (-3173 875);
FORCEADD TAP..6
R 2
(-3325 1025);
FORCEPROP 3 LASTPIN (-3375 1025) SIG_NAME P5E_CPU0_P1_TX_DP<13>
J 0
(-3365 1035);
DISPLAY 0.659574 (-3365 1035);
PAINT MONO (-3365 1035);
DISPLAY INVISIBLE (-3365 1035);
FORCEPROP 1 LASTPIN (-3375 1025) BN 13
J 2
(-3323 1033);
DISPLAY 0.489362 (-3323 1033);
PAINT MONO (-3323 1033);
FORCEPROP 2 LAST ROOM RISER1
J 0
(-3825 1075);
DISPLAY 0.829787 (-3825 1075);
PAINT RED (-3825 1075);
DISPLAY INVISIBLE (-3825 1075);
FORCEPROP 2 LAST BOM_COST IO_SLOT
J 0
(-3825 1125);
DISPLAY 0.829787 (-3825 1125);
DISPLAY INVISIBLE (-3825 1125);
FORCEPROP 2 LAST CDS_LIB standard
J 0
(-3325 1025);
DISPLAY INVISIBLE (-3325 1025);
FORCEPROP 1 LAST BODY_TYPE PLUMBING
J 2
(-3325 975);
DISPLAY 0.702128 (-3325 975);
PAINT GREEN (-3325 975);
DISPLAY INVISIBLE (-3325 975);
FORCEPROP 1 LAST HDL_TAP TRUE
J 2
(-3650 900);
DISPLAY 0.702128 (-3650 900);
PAINT GREEN (-3650 900);
DISPLAY INVISIBLE (-3650 900);
FORCEPROP 1 LAST PATH I248
J 2
(-3323 1025);
DISPLAY 0.872340 (-3323 1025);
PAINT GREEN (-3323 1025);
DISPLAY INVISIBLE (-3323 1025);
FORCEADD TAP..6
R 2
(-3325 925);
FORCEPROP 3 LASTPIN (-3375 925) SIG_NAME P5E_CPU0_P1_TX_DP<14>
J 0
(-3365 935);
DISPLAY 0.659574 (-3365 935);
PAINT MONO (-3365 935);
DISPLAY INVISIBLE (-3365 935);
FORCEPROP 1 LASTPIN (-3375 925) BN 14
J 2
(-3323 933);
DISPLAY 0.489362 (-3323 933);
PAINT MONO (-3323 933);
FORCEPROP 2 LAST ROOM RISER1
J 0
(-3825 975);
DISPLAY 0.829787 (-3825 975);
PAINT RED (-3825 975);
DISPLAY INVISIBLE (-3825 975);
FORCEPROP 2 LAST BOM_COST IO_SLOT
J 0
(-3825 1025);
DISPLAY 0.829787 (-3825 1025);
DISPLAY INVISIBLE (-3825 1025);
FORCEPROP 2 LAST CDS_LIB standard
J 0
(-3325 925);
DISPLAY INVISIBLE (-3325 925);
FORCEPROP 1 LAST BODY_TYPE PLUMBING
J 2
(-3325 875);
DISPLAY 0.702128 (-3325 875);
PAINT GREEN (-3325 875);
DISPLAY INVISIBLE (-3325 875);
FORCEPROP 1 LAST HDL_TAP TRUE
J 2
(-3650 800);
DISPLAY 0.702128 (-3650 800);
PAINT GREEN (-3650 800);
DISPLAY INVISIBLE (-3650 800);
FORCEPROP 1 LAST PATH I249
J 2
(-3323 925);
DISPLAY 0.872340 (-3323 925);
PAINT GREEN (-3323 925);
DISPLAY INVISIBLE (-3323 925);
FORCEADD TAP..6
R 2
(-3325 825);
FORCEPROP 3 LASTPIN (-3375 825) SIG_NAME P5E_CPU0_P1_TX_DP<15>
J 0
(-3365 835);
DISPLAY 0.659574 (-3365 835);
PAINT MONO (-3365 835);
DISPLAY INVISIBLE (-3365 835);
FORCEPROP 1 LASTPIN (-3375 825) BN 15
J 2
(-3323 833);
DISPLAY 0.489362 (-3323 833);
PAINT MONO (-3323 833);
FORCEPROP 2 LAST ROOM RISER1
J 0
(-3825 875);
DISPLAY 0.829787 (-3825 875);
PAINT RED (-3825 875);
DISPLAY INVISIBLE (-3825 875);
FORCEPROP 2 LAST BOM_COST IO_SLOT
J 0
(-3825 925);
DISPLAY 0.829787 (-3825 925);
DISPLAY INVISIBLE (-3825 925);
FORCEPROP 2 LAST CDS_LIB standard
J 0
(-3325 825);
DISPLAY INVISIBLE (-3325 825);
FORCEPROP 1 LAST BODY_TYPE PLUMBING
J 2
(-3325 775);
DISPLAY 0.702128 (-3325 775);
PAINT GREEN (-3325 775);
DISPLAY INVISIBLE (-3325 775);
FORCEPROP 1 LAST HDL_TAP TRUE
J 2
(-3650 700);
DISPLAY 0.702128 (-3650 700);
PAINT GREEN (-3650 700);
DISPLAY INVISIBLE (-3650 700);
FORCEPROP 1 LAST PATH I250
J 2
(-3323 825);
DISPLAY 0.872340 (-3323 825);
PAINT GREEN (-3323 825);
DISPLAY INVISIBLE (-3323 825);
FORCEADD TAP..6
R 2
(-3175 775);
FORCEPROP 3 LASTPIN (-3225 775) SIG_NAME P5E_CPU0_P1_TX_DN<15>
J 0
(-3215 785);
DISPLAY 0.659574 (-3215 785);
PAINT MONO (-3215 785);
DISPLAY INVISIBLE (-3215 785);
FORCEPROP 1 LASTPIN (-3225 775) BN 15
J 2
(-3173 783);
DISPLAY 0.489362 (-3173 783);
PAINT MONO (-3173 783);
FORCEPROP 2 LAST ROOM RISER1
J 0
(-3675 825);
DISPLAY 0.829787 (-3675 825);
PAINT RED (-3675 825);
DISPLAY INVISIBLE (-3675 825);
FORCEPROP 2 LAST BOM_COST IO_SLOT
J 0
(-3675 875);
DISPLAY 0.829787 (-3675 875);
DISPLAY INVISIBLE (-3675 875);
FORCEPROP 2 LAST CDS_LIB standard
J 0
(-3175 775);
DISPLAY INVISIBLE (-3175 775);
FORCEPROP 1 LAST BODY_TYPE PLUMBING
J 2
(-3175 725);
DISPLAY 0.702128 (-3175 725);
PAINT GREEN (-3175 725);
DISPLAY INVISIBLE (-3175 725);
FORCEPROP 1 LAST HDL_TAP TRUE
J 2
(-3500 650);
DISPLAY 0.702128 (-3500 650);
PAINT GREEN (-3500 650);
DISPLAY INVISIBLE (-3500 650);
FORCEPROP 1 LAST PATH I251
J 2
(-3173 775);
DISPLAY 0.872340 (-3173 775);
PAINT GREEN (-3173 775);
DISPLAY INVISIBLE (-3173 775);
FORCEADD TAP..6
(-6900 775);
FORCEPROP 3 LASTPIN (-6850 775) SIG_NAME P5E_CPU0_P1_RX_DN<15>
J 0
(-6840 785);
DISPLAY 0.659574 (-6840 785);
PAINT MONO (-6840 785);
DISPLAY INVISIBLE (-6840 785);
FORCEPROP 1 LASTPIN (-6850 775) BN 15
J 0
(-6902 783);
DISPLAY 0.489362 (-6902 783);
PAINT MONO (-6902 783);
FORCEPROP 2 LAST CDS_LIB standard
J 0
(-6900 775);
DISPLAY INVISIBLE (-6900 775);
FORCEPROP 1 LAST BODY_TYPE PLUMBING
J 0
(-6900 725);
DISPLAY 0.574468 (-6900 725);
PAINT GREEN (-6900 725);
DISPLAY INVISIBLE (-6900 725);
FORCEPROP 1 LAST HDL_TAP TRUE
J 0
(-6575 650);
DISPLAY 0.574468 (-6575 650);
PAINT GREEN (-6575 650);
DISPLAY INVISIBLE (-6575 650);
FORCEPROP 1 LAST PATH I292
J 0
(-6902 775);
DISPLAY 0.872340 (-6902 775);
PAINT GREEN (-6902 775);
DISPLAY INVISIBLE (-6902 775);
FORCEADD TAP..6
(-6900 875);
FORCEPROP 3 LASTPIN (-6850 875) SIG_NAME P5E_CPU0_P1_RX_DN<14>
J 0
(-6840 885);
DISPLAY 0.659574 (-6840 885);
PAINT MONO (-6840 885);
DISPLAY INVISIBLE (-6840 885);
FORCEPROP 1 LASTPIN (-6850 875) BN 14
J 0
(-6902 883);
DISPLAY 0.489362 (-6902 883);
PAINT MONO (-6902 883);
FORCEPROP 2 LAST CDS_LIB standard
J 0
(-6900 875);
DISPLAY INVISIBLE (-6900 875);
FORCEPROP 1 LAST BODY_TYPE PLUMBING
J 0
(-6900 825);
DISPLAY 0.574468 (-6900 825);
PAINT GREEN (-6900 825);
DISPLAY INVISIBLE (-6900 825);
FORCEPROP 1 LAST HDL_TAP TRUE
J 0
(-6575 750);
DISPLAY 0.574468 (-6575 750);
PAINT GREEN (-6575 750);
DISPLAY INVISIBLE (-6575 750);
FORCEPROP 1 LAST PATH I293
J 0
(-6902 875);
DISPLAY 0.872340 (-6902 875);
PAINT GREEN (-6902 875);
DISPLAY INVISIBLE (-6902 875);
FORCEADD TAP..6
(-6750 825);
FORCEPROP 3 LASTPIN (-6700 825) SIG_NAME P5E_CPU0_P1_RX_DP<15>
J 0
(-6690 835);
DISPLAY 0.659574 (-6690 835);
PAINT MONO (-6690 835);
DISPLAY INVISIBLE (-6690 835);
FORCEPROP 1 LASTPIN (-6700 825) BN 15
J 0
(-6752 833);
DISPLAY 0.489362 (-6752 833);
PAINT MONO (-6752 833);
FORCEPROP 2 LAST CDS_LIB standard
J 0
(-6750 825);
DISPLAY INVISIBLE (-6750 825);
FORCEPROP 1 LAST BODY_TYPE PLUMBING
J 0
(-6750 775);
DISPLAY 0.574468 (-6750 775);
PAINT GREEN (-6750 775);
DISPLAY INVISIBLE (-6750 775);
FORCEPROP 1 LAST HDL_TAP TRUE
J 0
(-6425 700);
DISPLAY 0.574468 (-6425 700);
PAINT GREEN (-6425 700);
DISPLAY INVISIBLE (-6425 700);
FORCEPROP 1 LAST PATH I294
J 0
(-6752 825);
DISPLAY 0.872340 (-6752 825);
PAINT GREEN (-6752 825);
DISPLAY INVISIBLE (-6752 825);
FORCEADD TAP..6
(-6750 925);
FORCEPROP 3 LASTPIN (-6700 925) SIG_NAME P5E_CPU0_P1_RX_DP<14>
J 0
(-6690 935);
DISPLAY 0.659574 (-6690 935);
PAINT MONO (-6690 935);
DISPLAY INVISIBLE (-6690 935);
FORCEPROP 1 LASTPIN (-6700 925) BN 14
J 0
(-6752 933);
DISPLAY 0.489362 (-6752 933);
PAINT MONO (-6752 933);
FORCEPROP 2 LAST CDS_LIB standard
J 0
(-6750 925);
DISPLAY INVISIBLE (-6750 925);
FORCEPROP 1 LAST BODY_TYPE PLUMBING
J 0
(-6750 875);
DISPLAY 0.574468 (-6750 875);
PAINT GREEN (-6750 875);
DISPLAY INVISIBLE (-6750 875);
FORCEPROP 1 LAST HDL_TAP TRUE
J 0
(-6425 800);
DISPLAY 0.574468 (-6425 800);
PAINT GREEN (-6425 800);
DISPLAY INVISIBLE (-6425 800);
FORCEPROP 1 LAST PATH I295
J 0
(-6752 925);
DISPLAY 0.872340 (-6752 925);
PAINT GREEN (-6752 925);
DISPLAY INVISIBLE (-6752 925);
FORCEADD TAP..6
(-6900 1075);
FORCEPROP 3 LASTPIN (-6850 1075) SIG_NAME P5E_CPU0_P1_RX_DN<12>
J 0
(-6840 1085);
DISPLAY 0.659574 (-6840 1085);
PAINT MONO (-6840 1085);
DISPLAY INVISIBLE (-6840 1085);
FORCEPROP 1 LASTPIN (-6850 1075) BN 12
J 0
(-6902 1083);
DISPLAY 0.489362 (-6902 1083);
PAINT MONO (-6902 1083);
FORCEPROP 2 LAST CDS_LIB standard
J 0
(-6900 1075);
DISPLAY INVISIBLE (-6900 1075);
FORCEPROP 1 LAST BODY_TYPE PLUMBING
J 0
(-6900 1025);
DISPLAY 0.574468 (-6900 1025);
PAINT GREEN (-6900 1025);
DISPLAY INVISIBLE (-6900 1025);
FORCEPROP 1 LAST HDL_TAP TRUE
J 0
(-6575 950);
DISPLAY 0.574468 (-6575 950);
PAINT GREEN (-6575 950);
DISPLAY INVISIBLE (-6575 950);
FORCEPROP 1 LAST PATH I296
J 0
(-6902 1075);
DISPLAY 0.872340 (-6902 1075);
PAINT GREEN (-6902 1075);
DISPLAY INVISIBLE (-6902 1075);
FORCEADD TAP..6
(-6900 975);
FORCEPROP 3 LASTPIN (-6850 975) SIG_NAME P5E_CPU0_P1_RX_DN<13>
J 0
(-6840 985);
DISPLAY 0.659574 (-6840 985);
PAINT MONO (-6840 985);
DISPLAY INVISIBLE (-6840 985);
FORCEPROP 1 LASTPIN (-6850 975) BN 13
J 0
(-6902 983);
DISPLAY 0.489362 (-6902 983);
PAINT MONO (-6902 983);
FORCEPROP 2 LAST CDS_LIB standard
J 0
(-6900 975);
DISPLAY INVISIBLE (-6900 975);
FORCEPROP 1 LAST BODY_TYPE PLUMBING
J 0
(-6900 925);
DISPLAY 0.574468 (-6900 925);
PAINT GREEN (-6900 925);
DISPLAY INVISIBLE (-6900 925);
FORCEPROP 1 LAST HDL_TAP TRUE
J 0
(-6575 850);
DISPLAY 0.574468 (-6575 850);
PAINT GREEN (-6575 850);
DISPLAY INVISIBLE (-6575 850);
FORCEPROP 1 LAST PATH I297
J 0
(-6902 975);
DISPLAY 0.872340 (-6902 975);
PAINT GREEN (-6902 975);
DISPLAY INVISIBLE (-6902 975);
FORCEADD TAP..6
(-6900 1175);
FORCEPROP 3 LASTPIN (-6850 1175) SIG_NAME P5E_CPU0_P1_RX_DN<11>
J 0
(-6840 1185);
DISPLAY 0.659574 (-6840 1185);
PAINT MONO (-6840 1185);
DISPLAY INVISIBLE (-6840 1185);
FORCEPROP 1 LASTPIN (-6850 1175) BN 11
J 0
(-6902 1183);
DISPLAY 0.489362 (-6902 1183);
PAINT MONO (-6902 1183);
FORCEPROP 2 LAST CDS_LIB standard
J 0
(-6900 1175);
DISPLAY INVISIBLE (-6900 1175);
FORCEPROP 1 LAST BODY_TYPE PLUMBING
J 0
(-6900 1125);
DISPLAY 0.574468 (-6900 1125);
PAINT GREEN (-6900 1125);
DISPLAY INVISIBLE (-6900 1125);
FORCEPROP 1 LAST HDL_TAP TRUE
J 0
(-6575 1050);
DISPLAY 0.574468 (-6575 1050);
PAINT GREEN (-6575 1050);
DISPLAY INVISIBLE (-6575 1050);
FORCEPROP 1 LAST PATH I298
J 0
(-6902 1175);
DISPLAY 0.872340 (-6902 1175);
PAINT GREEN (-6902 1175);
DISPLAY INVISIBLE (-6902 1175);
FORCEADD TAP..6
(-6750 1025);
FORCEPROP 3 LASTPIN (-6700 1025) SIG_NAME P5E_CPU0_P1_RX_DP<13>
J 0
(-6690 1035);
DISPLAY 0.659574 (-6690 1035);
PAINT MONO (-6690 1035);
DISPLAY INVISIBLE (-6690 1035);
FORCEPROP 1 LASTPIN (-6700 1025) BN 13
J 0
(-6752 1033);
DISPLAY 0.489362 (-6752 1033);
PAINT MONO (-6752 1033);
FORCEPROP 2 LAST CDS_LIB standard
J 0
(-6750 1025);
DISPLAY INVISIBLE (-6750 1025);
FORCEPROP 1 LAST BODY_TYPE PLUMBING
J 0
(-6750 975);
DISPLAY 0.574468 (-6750 975);
PAINT GREEN (-6750 975);
DISPLAY INVISIBLE (-6750 975);
FORCEPROP 1 LAST HDL_TAP TRUE
J 0
(-6425 900);
DISPLAY 0.574468 (-6425 900);
PAINT GREEN (-6425 900);
DISPLAY INVISIBLE (-6425 900);
FORCEPROP 1 LAST PATH I299
J 0
(-6752 1025);
DISPLAY 0.872340 (-6752 1025);
PAINT GREEN (-6752 1025);
DISPLAY INVISIBLE (-6752 1025);
FORCEADD TAP..6
(-6750 1125);
FORCEPROP 3 LASTPIN (-6700 1125) SIG_NAME P5E_CPU0_P1_RX_DP<12>
J 0
(-6690 1135);
DISPLAY 0.659574 (-6690 1135);
PAINT MONO (-6690 1135);
DISPLAY INVISIBLE (-6690 1135);
FORCEPROP 1 LASTPIN (-6700 1125) BN 12
J 0
(-6752 1133);
DISPLAY 0.489362 (-6752 1133);
PAINT MONO (-6752 1133);
FORCEPROP 2 LAST CDS_LIB standard
J 0
(-6750 1125);
DISPLAY INVISIBLE (-6750 1125);
FORCEPROP 1 LAST BODY_TYPE PLUMBING
J 0
(-6750 1075);
DISPLAY 0.574468 (-6750 1075);
PAINT GREEN (-6750 1075);
DISPLAY INVISIBLE (-6750 1075);
FORCEPROP 1 LAST HDL_TAP TRUE
J 0
(-6425 1000);
DISPLAY 0.574468 (-6425 1000);
PAINT GREEN (-6425 1000);
DISPLAY INVISIBLE (-6425 1000);
FORCEPROP 1 LAST PATH I300
J 0
(-6752 1125);
DISPLAY 0.872340 (-6752 1125);
PAINT GREEN (-6752 1125);
DISPLAY INVISIBLE (-6752 1125);
FORCEADD TAP..6
(-6900 1275);
FORCEPROP 3 LASTPIN (-6850 1275) SIG_NAME P5E_CPU0_P1_RX_DN<10>
J 0
(-6840 1285);
DISPLAY 0.659574 (-6840 1285);
PAINT MONO (-6840 1285);
DISPLAY INVISIBLE (-6840 1285);
FORCEPROP 1 LASTPIN (-6850 1275) BN 10
J 0
(-6902 1283);
DISPLAY 0.489362 (-6902 1283);
PAINT MONO (-6902 1283);
FORCEPROP 2 LAST CDS_LIB standard
J 0
(-6900 1275);
DISPLAY INVISIBLE (-6900 1275);
FORCEPROP 1 LAST BODY_TYPE PLUMBING
J 0
(-6900 1225);
DISPLAY 0.574468 (-6900 1225);
PAINT GREEN (-6900 1225);
DISPLAY INVISIBLE (-6900 1225);
FORCEPROP 1 LAST HDL_TAP TRUE
J 0
(-6575 1150);
DISPLAY 0.574468 (-6575 1150);
PAINT GREEN (-6575 1150);
DISPLAY INVISIBLE (-6575 1150);
FORCEPROP 1 LAST PATH I301
J 0
(-6902 1275);
DISPLAY 0.872340 (-6902 1275);
PAINT GREEN (-6902 1275);
DISPLAY INVISIBLE (-6902 1275);
FORCEADD TAP..6
(-6900 1375);
FORCEPROP 3 LASTPIN (-6850 1375) SIG_NAME P5E_CPU0_P1_RX_DN<9>
J 0
(-6840 1385);
DISPLAY 0.659574 (-6840 1385);
PAINT MONO (-6840 1385);
DISPLAY INVISIBLE (-6840 1385);
FORCEPROP 1 LASTPIN (-6850 1375) BN 9
J 0
(-6902 1383);
DISPLAY 0.489362 (-6902 1383);
PAINT MONO (-6902 1383);
FORCEPROP 2 LAST CDS_LIB standard
J 0
(-6900 1375);
DISPLAY INVISIBLE (-6900 1375);
FORCEPROP 1 LAST BODY_TYPE PLUMBING
J 0
(-6900 1325);
DISPLAY 0.574468 (-6900 1325);
PAINT GREEN (-6900 1325);
DISPLAY INVISIBLE (-6900 1325);
FORCEPROP 1 LAST HDL_TAP TRUE
J 0
(-6575 1250);
DISPLAY 0.574468 (-6575 1250);
PAINT GREEN (-6575 1250);
DISPLAY INVISIBLE (-6575 1250);
FORCEPROP 1 LAST PATH I302
J 0
(-6902 1375);
DISPLAY 0.872340 (-6902 1375);
PAINT GREEN (-6902 1375);
DISPLAY INVISIBLE (-6902 1375);
FORCEADD TAP..6
(-6750 1225);
FORCEPROP 3 LASTPIN (-6700 1225) SIG_NAME P5E_CPU0_P1_RX_DP<11>
J 0
(-6690 1235);
DISPLAY 0.659574 (-6690 1235);
PAINT MONO (-6690 1235);
DISPLAY INVISIBLE (-6690 1235);
FORCEPROP 1 LASTPIN (-6700 1225) BN 11
J 0
(-6752 1233);
DISPLAY 0.489362 (-6752 1233);
PAINT MONO (-6752 1233);
FORCEPROP 2 LAST CDS_LIB standard
J 0
(-6750 1225);
DISPLAY INVISIBLE (-6750 1225);
FORCEPROP 1 LAST BODY_TYPE PLUMBING
J 0
(-6750 1175);
DISPLAY 0.574468 (-6750 1175);
PAINT GREEN (-6750 1175);
DISPLAY INVISIBLE (-6750 1175);
FORCEPROP 1 LAST HDL_TAP TRUE
J 0
(-6425 1100);
DISPLAY 0.574468 (-6425 1100);
PAINT GREEN (-6425 1100);
DISPLAY INVISIBLE (-6425 1100);
FORCEPROP 1 LAST PATH I303
J 0
(-6752 1225);
DISPLAY 0.872340 (-6752 1225);
PAINT GREEN (-6752 1225);
DISPLAY INVISIBLE (-6752 1225);
FORCEADD TAP..6
(-6750 1325);
FORCEPROP 3 LASTPIN (-6700 1325) SIG_NAME P5E_CPU0_P1_RX_DP<10>
J 0
(-6690 1335);
DISPLAY 0.659574 (-6690 1335);
PAINT MONO (-6690 1335);
DISPLAY INVISIBLE (-6690 1335);
FORCEPROP 1 LASTPIN (-6700 1325) BN 10
J 0
(-6752 1333);
DISPLAY 0.489362 (-6752 1333);
PAINT MONO (-6752 1333);
FORCEPROP 2 LAST CDS_LIB standard
J 0
(-6750 1325);
DISPLAY INVISIBLE (-6750 1325);
FORCEPROP 1 LAST BODY_TYPE PLUMBING
J 0
(-6750 1275);
DISPLAY 0.574468 (-6750 1275);
PAINT GREEN (-6750 1275);
DISPLAY INVISIBLE (-6750 1275);
FORCEPROP 1 LAST HDL_TAP TRUE
J 0
(-6425 1200);
DISPLAY 0.574468 (-6425 1200);
PAINT GREEN (-6425 1200);
DISPLAY INVISIBLE (-6425 1200);
FORCEPROP 1 LAST PATH I304
J 0
(-6752 1325);
DISPLAY 0.872340 (-6752 1325);
PAINT GREEN (-6752 1325);
DISPLAY INVISIBLE (-6752 1325);
FORCEADD TAP..6
(-6750 1425);
FORCEPROP 3 LASTPIN (-6700 1425) SIG_NAME P5E_CPU0_P1_RX_DP<9>
J 0
(-6690 1435);
DISPLAY 0.659574 (-6690 1435);
PAINT MONO (-6690 1435);
DISPLAY INVISIBLE (-6690 1435);
FORCEPROP 1 LASTPIN (-6700 1425) BN 9
J 0
(-6752 1433);
DISPLAY 0.489362 (-6752 1433);
PAINT MONO (-6752 1433);
FORCEPROP 2 LAST CDS_LIB standard
J 0
(-6750 1425);
DISPLAY INVISIBLE (-6750 1425);
FORCEPROP 1 LAST BODY_TYPE PLUMBING
J 0
(-6750 1375);
DISPLAY 0.574468 (-6750 1375);
PAINT GREEN (-6750 1375);
DISPLAY INVISIBLE (-6750 1375);
FORCEPROP 1 LAST HDL_TAP TRUE
J 0
(-6425 1300);
DISPLAY 0.574468 (-6425 1300);
PAINT GREEN (-6425 1300);
DISPLAY INVISIBLE (-6425 1300);
FORCEPROP 1 LAST PATH I305
J 0
(-6752 1425);
DISPLAY 0.872340 (-6752 1425);
PAINT GREEN (-6752 1425);
DISPLAY INVISIBLE (-6752 1425);
FORCEADD OFFPAGE..1
(-8125 2500);
FORCEPROP 2 LAST $XR0 285 
J 0
(-8407 2500);
DISPLAY 0.638298 (-8407 2500);
PAINT MONO (-8407 2500);
FORCEPROP 2 LAST CDS_LIB standard
J 0
(-8125 2500);
DISPLAY INVISIBLE (-8125 2500);
FORCEPROP 1 LAST OFFPAGE TRUE
J 0
(-7800 2375);
DISPLAY 0.872340 (-7800 2375);
PAINT GREEN (-7800 2375);
DISPLAY INVISIBLE (-7800 2375);
FORCEPROP 1 LAST COMMENT_BODY TRUE
J 0
(-8000 2400);
DISPLAY 0.872340 (-8000 2400);
PAINT GREEN (-8000 2400);
DISPLAY INVISIBLE (-8000 2400);
FORCEPROP 2 LAST PATH I306
J 0
(-8075 2575);
DISPLAY 1.021277 (-8075 2575);
DISPLAY INVISIBLE (-8075 2575);
FORCEADD OFFPAGE..1
(-8125 2550);
FORCEPROP 2 LAST $XR0 285 
J 0
(-8407 2550);
DISPLAY 0.638298 (-8407 2550);
PAINT MONO (-8407 2550);
FORCEPROP 2 LAST CDS_LIB standard
J 0
(-8125 2550);
DISPLAY INVISIBLE (-8125 2550);
FORCEPROP 1 LAST OFFPAGE TRUE
J 0
(-7800 2425);
DISPLAY 0.872340 (-7800 2425);
PAINT GREEN (-7800 2425);
DISPLAY INVISIBLE (-7800 2425);
FORCEPROP 1 LAST COMMENT_BODY TRUE
J 0
(-8000 2450);
DISPLAY 0.872340 (-8000 2450);
PAINT GREEN (-8000 2450);
DISPLAY INVISIBLE (-8000 2450);
FORCEPROP 2 LAST PATH I307
J 0
(-8075 2625);
DISPLAY 1.021277 (-8075 2625);
DISPLAY INVISIBLE (-8075 2625);
FORCEADD TAP..6
(-6900 1575);
FORCEPROP 3 LASTPIN (-6850 1575) SIG_NAME P5E_CPU0_P1_RX_DN<7>
J 0
(-6840 1585);
DISPLAY 0.659574 (-6840 1585);
PAINT MONO (-6840 1585);
DISPLAY INVISIBLE (-6840 1585);
FORCEPROP 1 LASTPIN (-6850 1575) BN 7
J 0
(-6902 1583);
DISPLAY 0.489362 (-6902 1583);
PAINT MONO (-6902 1583);
FORCEPROP 2 LAST CDS_LIB standard
J 0
(-6900 1575);
DISPLAY INVISIBLE (-6900 1575);
FORCEPROP 1 LAST BODY_TYPE PLUMBING
J 0
(-6900 1525);
DISPLAY 0.574468 (-6900 1525);
PAINT GREEN (-6900 1525);
DISPLAY INVISIBLE (-6900 1525);
FORCEPROP 1 LAST HDL_TAP TRUE
J 0
(-6575 1450);
DISPLAY 0.574468 (-6575 1450);
PAINT GREEN (-6575 1450);
DISPLAY INVISIBLE (-6575 1450);
FORCEPROP 1 LAST PATH I308
J 0
(-6902 1575);
DISPLAY 0.872340 (-6902 1575);
PAINT GREEN (-6902 1575);
DISPLAY INVISIBLE (-6902 1575);
FORCEADD TAP..6
(-6900 1475);
FORCEPROP 3 LASTPIN (-6850 1475) SIG_NAME P5E_CPU0_P1_RX_DN<8>
J 0
(-6840 1485);
DISPLAY 0.659574 (-6840 1485);
PAINT MONO (-6840 1485);
DISPLAY INVISIBLE (-6840 1485);
FORCEPROP 1 LASTPIN (-6850 1475) BN 8
J 0
(-6902 1483);
DISPLAY 0.489362 (-6902 1483);
PAINT MONO (-6902 1483);
FORCEPROP 2 LAST CDS_LIB standard
J 0
(-6900 1475);
DISPLAY INVISIBLE (-6900 1475);
FORCEPROP 1 LAST BODY_TYPE PLUMBING
J 0
(-6900 1425);
DISPLAY 0.574468 (-6900 1425);
PAINT GREEN (-6900 1425);
DISPLAY INVISIBLE (-6900 1425);
FORCEPROP 1 LAST HDL_TAP TRUE
J 0
(-6575 1350);
DISPLAY 0.574468 (-6575 1350);
PAINT GREEN (-6575 1350);
DISPLAY INVISIBLE (-6575 1350);
FORCEPROP 1 LAST PATH I309
J 0
(-6902 1475);
DISPLAY 0.872340 (-6902 1475);
PAINT GREEN (-6902 1475);
DISPLAY INVISIBLE (-6902 1475);
FORCEADD TAP..6
(-6900 1675);
FORCEPROP 3 LASTPIN (-6850 1675) SIG_NAME P5E_CPU0_P1_RX_DN<6>
J 0
(-6840 1685);
DISPLAY 0.659574 (-6840 1685);
PAINT MONO (-6840 1685);
DISPLAY INVISIBLE (-6840 1685);
FORCEPROP 1 LASTPIN (-6850 1675) BN 6
J 0
(-6902 1683);
DISPLAY 0.489362 (-6902 1683);
PAINT MONO (-6902 1683);
FORCEPROP 2 LAST CDS_LIB standard
J 0
(-6900 1675);
DISPLAY INVISIBLE (-6900 1675);
FORCEPROP 1 LAST BODY_TYPE PLUMBING
J 0
(-6900 1625);
DISPLAY 0.574468 (-6900 1625);
PAINT GREEN (-6900 1625);
DISPLAY INVISIBLE (-6900 1625);
FORCEPROP 1 LAST HDL_TAP TRUE
J 0
(-6575 1550);
DISPLAY 0.574468 (-6575 1550);
PAINT GREEN (-6575 1550);
DISPLAY INVISIBLE (-6575 1550);
FORCEPROP 1 LAST PATH I310
J 0
(-6902 1675);
DISPLAY 0.872340 (-6902 1675);
PAINT GREEN (-6902 1675);
DISPLAY INVISIBLE (-6902 1675);
FORCEADD TAP..6
(-6750 1525);
FORCEPROP 3 LASTPIN (-6700 1525) SIG_NAME P5E_CPU0_P1_RX_DP<8>
J 0
(-6690 1535);
DISPLAY 0.659574 (-6690 1535);
PAINT MONO (-6690 1535);
DISPLAY INVISIBLE (-6690 1535);
FORCEPROP 1 LASTPIN (-6700 1525) BN 8
J 0
(-6752 1533);
DISPLAY 0.489362 (-6752 1533);
PAINT MONO (-6752 1533);
FORCEPROP 2 LAST CDS_LIB standard
J 0
(-6750 1525);
DISPLAY INVISIBLE (-6750 1525);
FORCEPROP 1 LAST BODY_TYPE PLUMBING
J 0
(-6750 1475);
DISPLAY 0.574468 (-6750 1475);
PAINT GREEN (-6750 1475);
DISPLAY INVISIBLE (-6750 1475);
FORCEPROP 1 LAST HDL_TAP TRUE
J 0
(-6425 1400);
DISPLAY 0.574468 (-6425 1400);
PAINT GREEN (-6425 1400);
DISPLAY INVISIBLE (-6425 1400);
FORCEPROP 1 LAST PATH I311
J 0
(-6752 1525);
DISPLAY 0.872340 (-6752 1525);
PAINT GREEN (-6752 1525);
DISPLAY INVISIBLE (-6752 1525);
FORCEADD TAP..6
(-6750 1625);
FORCEPROP 3 LASTPIN (-6700 1625) SIG_NAME P5E_CPU0_P1_RX_DP<7>
J 0
(-6690 1635);
DISPLAY 0.659574 (-6690 1635);
PAINT MONO (-6690 1635);
DISPLAY INVISIBLE (-6690 1635);
FORCEPROP 1 LASTPIN (-6700 1625) BN 7
J 0
(-6752 1633);
DISPLAY 0.489362 (-6752 1633);
PAINT MONO (-6752 1633);
FORCEPROP 2 LAST CDS_LIB standard
J 0
(-6750 1625);
DISPLAY INVISIBLE (-6750 1625);
FORCEPROP 1 LAST BODY_TYPE PLUMBING
J 0
(-6750 1575);
DISPLAY 0.574468 (-6750 1575);
PAINT GREEN (-6750 1575);
DISPLAY INVISIBLE (-6750 1575);
FORCEPROP 1 LAST HDL_TAP TRUE
J 0
(-6425 1500);
DISPLAY 0.574468 (-6425 1500);
PAINT GREEN (-6425 1500);
DISPLAY INVISIBLE (-6425 1500);
FORCEPROP 1 LAST PATH I312
J 0
(-6752 1625);
DISPLAY 0.872340 (-6752 1625);
PAINT GREEN (-6752 1625);
DISPLAY INVISIBLE (-6752 1625);
FORCEADD TAP..6
(-6750 1725);
FORCEPROP 3 LASTPIN (-6700 1725) SIG_NAME P5E_CPU0_P1_RX_DP<6>
J 0
(-6690 1735);
DISPLAY 0.659574 (-6690 1735);
PAINT MONO (-6690 1735);
DISPLAY INVISIBLE (-6690 1735);
FORCEPROP 1 LASTPIN (-6700 1725) BN 6
J 0
(-6752 1733);
DISPLAY 0.489362 (-6752 1733);
PAINT MONO (-6752 1733);
FORCEPROP 2 LAST CDS_LIB standard
J 0
(-6750 1725);
DISPLAY INVISIBLE (-6750 1725);
FORCEPROP 1 LAST BODY_TYPE PLUMBING
J 0
(-6750 1675);
DISPLAY 0.574468 (-6750 1675);
PAINT GREEN (-6750 1675);
DISPLAY INVISIBLE (-6750 1675);
FORCEPROP 1 LAST HDL_TAP TRUE
J 0
(-6425 1600);
DISPLAY 0.574468 (-6425 1600);
PAINT GREEN (-6425 1600);
DISPLAY INVISIBLE (-6425 1600);
FORCEPROP 1 LAST PATH I313
J 0
(-6752 1725);
DISPLAY 0.872340 (-6752 1725);
PAINT GREEN (-6752 1725);
DISPLAY INVISIBLE (-6752 1725);
FORCEADD TAP..6
(-6900 1775);
FORCEPROP 3 LASTPIN (-6850 1775) SIG_NAME P5E_CPU0_P1_RX_DN<5>
J 0
(-6840 1785);
DISPLAY 0.659574 (-6840 1785);
PAINT MONO (-6840 1785);
DISPLAY INVISIBLE (-6840 1785);
FORCEPROP 1 LASTPIN (-6850 1775) BN 5
J 0
(-6902 1783);
DISPLAY 0.489362 (-6902 1783);
PAINT MONO (-6902 1783);
FORCEPROP 2 LAST CDS_LIB standard
J 0
(-6900 1775);
DISPLAY INVISIBLE (-6900 1775);
FORCEPROP 1 LAST BODY_TYPE PLUMBING
J 0
(-6900 1725);
DISPLAY 0.574468 (-6900 1725);
PAINT GREEN (-6900 1725);
DISPLAY INVISIBLE (-6900 1725);
FORCEPROP 1 LAST HDL_TAP TRUE
J 0
(-6575 1650);
DISPLAY 0.574468 (-6575 1650);
PAINT GREEN (-6575 1650);
DISPLAY INVISIBLE (-6575 1650);
FORCEPROP 1 LAST PATH I314
J 0
(-6902 1775);
DISPLAY 0.872340 (-6902 1775);
PAINT GREEN (-6902 1775);
DISPLAY INVISIBLE (-6902 1775);
FORCEADD TAP..6
(-6900 1975);
FORCEPROP 3 LASTPIN (-6850 1975) SIG_NAME P5E_CPU0_P1_RX_DN<3>
J 0
(-6840 1985);
DISPLAY 0.659574 (-6840 1985);
PAINT MONO (-6840 1985);
DISPLAY INVISIBLE (-6840 1985);
FORCEPROP 1 LASTPIN (-6850 1975) BN 3
J 0
(-6902 1983);
DISPLAY 0.489362 (-6902 1983);
PAINT MONO (-6902 1983);
FORCEPROP 2 LAST CDS_LIB standard
J 0
(-6900 1975);
DISPLAY INVISIBLE (-6900 1975);
FORCEPROP 1 LAST BODY_TYPE PLUMBING
J 0
(-6900 1925);
DISPLAY 0.574468 (-6900 1925);
PAINT GREEN (-6900 1925);
DISPLAY INVISIBLE (-6900 1925);
FORCEPROP 1 LAST HDL_TAP TRUE
J 0
(-6575 1850);
DISPLAY 0.574468 (-6575 1850);
PAINT GREEN (-6575 1850);
DISPLAY INVISIBLE (-6575 1850);
FORCEPROP 1 LAST PATH I315
J 0
(-6902 1975);
DISPLAY 0.872340 (-6902 1975);
PAINT GREEN (-6902 1975);
DISPLAY INVISIBLE (-6902 1975);
FORCEADD TAP..6
(-6900 1875);
FORCEPROP 3 LASTPIN (-6850 1875) SIG_NAME P5E_CPU0_P1_RX_DN<4>
J 0
(-6840 1885);
DISPLAY 0.659574 (-6840 1885);
PAINT MONO (-6840 1885);
DISPLAY INVISIBLE (-6840 1885);
FORCEPROP 1 LASTPIN (-6850 1875) BN 4
J 0
(-6902 1883);
DISPLAY 0.489362 (-6902 1883);
PAINT MONO (-6902 1883);
FORCEPROP 2 LAST CDS_LIB standard
J 0
(-6900 1875);
DISPLAY INVISIBLE (-6900 1875);
FORCEPROP 1 LAST BODY_TYPE PLUMBING
J 0
(-6900 1825);
DISPLAY 0.574468 (-6900 1825);
PAINT GREEN (-6900 1825);
DISPLAY INVISIBLE (-6900 1825);
FORCEPROP 1 LAST HDL_TAP TRUE
J 0
(-6575 1750);
DISPLAY 0.574468 (-6575 1750);
PAINT GREEN (-6575 1750);
DISPLAY INVISIBLE (-6575 1750);
FORCEPROP 1 LAST PATH I316
J 0
(-6902 1875);
DISPLAY 0.872340 (-6902 1875);
PAINT GREEN (-6902 1875);
DISPLAY INVISIBLE (-6902 1875);
FORCEADD TAP..6
(-6750 1825);
FORCEPROP 3 LASTPIN (-6700 1825) SIG_NAME P5E_CPU0_P1_RX_DP<5>
J 0
(-6690 1835);
DISPLAY 0.659574 (-6690 1835);
PAINT MONO (-6690 1835);
DISPLAY INVISIBLE (-6690 1835);
FORCEPROP 1 LASTPIN (-6700 1825) BN 5
J 0
(-6752 1833);
DISPLAY 0.489362 (-6752 1833);
PAINT MONO (-6752 1833);
FORCEPROP 2 LAST CDS_LIB standard
J 0
(-6750 1825);
DISPLAY INVISIBLE (-6750 1825);
FORCEPROP 1 LAST BODY_TYPE PLUMBING
J 0
(-6750 1775);
DISPLAY 0.574468 (-6750 1775);
PAINT GREEN (-6750 1775);
DISPLAY INVISIBLE (-6750 1775);
FORCEPROP 1 LAST HDL_TAP TRUE
J 0
(-6425 1700);
DISPLAY 0.574468 (-6425 1700);
PAINT GREEN (-6425 1700);
DISPLAY INVISIBLE (-6425 1700);
FORCEPROP 1 LAST PATH I317
J 0
(-6752 1825);
DISPLAY 0.872340 (-6752 1825);
PAINT GREEN (-6752 1825);
DISPLAY INVISIBLE (-6752 1825);
FORCEADD TAP..6
(-6750 1925);
FORCEPROP 3 LASTPIN (-6700 1925) SIG_NAME P5E_CPU0_P1_RX_DP<4>
J 0
(-6690 1935);
DISPLAY 0.659574 (-6690 1935);
PAINT MONO (-6690 1935);
DISPLAY INVISIBLE (-6690 1935);
FORCEPROP 1 LASTPIN (-6700 1925) BN 4
J 0
(-6752 1933);
DISPLAY 0.489362 (-6752 1933);
PAINT MONO (-6752 1933);
FORCEPROP 2 LAST CDS_LIB standard
J 0
(-6750 1925);
DISPLAY INVISIBLE (-6750 1925);
FORCEPROP 1 LAST BODY_TYPE PLUMBING
J 0
(-6750 1875);
DISPLAY 0.574468 (-6750 1875);
PAINT GREEN (-6750 1875);
DISPLAY INVISIBLE (-6750 1875);
FORCEPROP 1 LAST HDL_TAP TRUE
J 0
(-6425 1800);
DISPLAY 0.574468 (-6425 1800);
PAINT GREEN (-6425 1800);
DISPLAY INVISIBLE (-6425 1800);
FORCEPROP 1 LAST PATH I318
J 0
(-6752 1925);
DISPLAY 0.872340 (-6752 1925);
PAINT GREEN (-6752 1925);
DISPLAY INVISIBLE (-6752 1925);
FORCEADD TAP..6
(-6900 2075);
FORCEPROP 3 LASTPIN (-6850 2075) SIG_NAME P5E_CPU0_P1_RX_DN<2>
J 0
(-6840 2085);
DISPLAY 0.659574 (-6840 2085);
PAINT MONO (-6840 2085);
DISPLAY INVISIBLE (-6840 2085);
FORCEPROP 1 LASTPIN (-6850 2075) BN 2
J 0
(-6902 2083);
DISPLAY 0.489362 (-6902 2083);
PAINT MONO (-6902 2083);
FORCEPROP 2 LAST CDS_LIB standard
J 0
(-6900 2075);
DISPLAY INVISIBLE (-6900 2075);
FORCEPROP 1 LAST BODY_TYPE PLUMBING
J 0
(-6900 2025);
DISPLAY 0.574468 (-6900 2025);
PAINT GREEN (-6900 2025);
DISPLAY INVISIBLE (-6900 2025);
FORCEPROP 1 LAST HDL_TAP TRUE
J 0
(-6575 1950);
DISPLAY 0.574468 (-6575 1950);
PAINT GREEN (-6575 1950);
DISPLAY INVISIBLE (-6575 1950);
FORCEPROP 1 LAST PATH I319
J 0
(-6902 2075);
DISPLAY 0.872340 (-6902 2075);
PAINT GREEN (-6902 2075);
DISPLAY INVISIBLE (-6902 2075);
FORCEADD TAP..6
(-6900 2175);
FORCEPROP 3 LASTPIN (-6850 2175) SIG_NAME P5E_CPU0_P1_RX_DN<1>
J 0
(-6840 2185);
DISPLAY 0.659574 (-6840 2185);
PAINT MONO (-6840 2185);
DISPLAY INVISIBLE (-6840 2185);
FORCEPROP 1 LASTPIN (-6850 2175) BN 1
J 0
(-6902 2183);
DISPLAY 0.489362 (-6902 2183);
PAINT MONO (-6902 2183);
FORCEPROP 2 LAST CDS_LIB mstr_standard
J 0
(-6900 2175);
DISPLAY INVISIBLE (-6900 2175);
FORCEPROP 1 LAST BODY_TYPE PLUMBING
J 0
(-6900 2125);
DISPLAY 0.574468 (-6900 2125);
PAINT GREEN (-6900 2125);
DISPLAY INVISIBLE (-6900 2125);
FORCEPROP 1 LAST HDL_TAP TRUE
J 0
(-6575 2050);
DISPLAY 0.574468 (-6575 2050);
PAINT GREEN (-6575 2050);
DISPLAY INVISIBLE (-6575 2050);
FORCEPROP 1 LAST PATH I320
J 0
(-6902 2175);
DISPLAY 0.872340 (-6902 2175);
PAINT GREEN (-6902 2175);
DISPLAY INVISIBLE (-6902 2175);
FORCEADD TAP..6
(-6750 2025);
FORCEPROP 3 LASTPIN (-6700 2025) SIG_NAME P5E_CPU0_P1_RX_DP<3>
J 0
(-6690 2035);
DISPLAY 0.659574 (-6690 2035);
PAINT MONO (-6690 2035);
DISPLAY INVISIBLE (-6690 2035);
FORCEPROP 1 LASTPIN (-6700 2025) BN 3
J 0
(-6752 2033);
DISPLAY 0.489362 (-6752 2033);
PAINT MONO (-6752 2033);
FORCEPROP 2 LAST CDS_LIB standard
J 0
(-6750 2025);
DISPLAY INVISIBLE (-6750 2025);
FORCEPROP 1 LAST BODY_TYPE PLUMBING
J 0
(-6750 1975);
DISPLAY 0.574468 (-6750 1975);
PAINT GREEN (-6750 1975);
DISPLAY INVISIBLE (-6750 1975);
FORCEPROP 1 LAST HDL_TAP TRUE
J 0
(-6425 1900);
DISPLAY 0.574468 (-6425 1900);
PAINT GREEN (-6425 1900);
DISPLAY INVISIBLE (-6425 1900);
FORCEPROP 1 LAST PATH I321
J 0
(-6752 2025);
DISPLAY 0.872340 (-6752 2025);
PAINT GREEN (-6752 2025);
DISPLAY INVISIBLE (-6752 2025);
FORCEADD TAP..6
(-6750 2125);
FORCEPROP 3 LASTPIN (-6700 2125) SIG_NAME P5E_CPU0_P1_RX_DP<2>
J 0
(-6690 2135);
DISPLAY 0.659574 (-6690 2135);
PAINT MONO (-6690 2135);
DISPLAY INVISIBLE (-6690 2135);
FORCEPROP 1 LASTPIN (-6700 2125) BN 2
J 0
(-6752 2133);
DISPLAY 0.489362 (-6752 2133);
PAINT MONO (-6752 2133);
FORCEPROP 2 LAST CDS_LIB mstr_standard
J 0
(-6750 2125);
DISPLAY INVISIBLE (-6750 2125);
FORCEPROP 1 LAST BODY_TYPE PLUMBING
J 0
(-6750 2075);
DISPLAY 0.574468 (-6750 2075);
PAINT GREEN (-6750 2075);
DISPLAY INVISIBLE (-6750 2075);
FORCEPROP 1 LAST HDL_TAP TRUE
J 0
(-6425 2000);
DISPLAY 0.574468 (-6425 2000);
PAINT GREEN (-6425 2000);
DISPLAY INVISIBLE (-6425 2000);
FORCEPROP 1 LAST PATH I322
J 0
(-6752 2125);
DISPLAY 0.872340 (-6752 2125);
PAINT GREEN (-6752 2125);
DISPLAY INVISIBLE (-6752 2125);
FORCEADD TAP..6
(-6750 2225);
FORCEPROP 3 LASTPIN (-6700 2225) SIG_NAME P5E_CPU0_P1_RX_DP<1>
J 0
(-6690 2235);
DISPLAY 0.659574 (-6690 2235);
PAINT MONO (-6690 2235);
DISPLAY INVISIBLE (-6690 2235);
FORCEPROP 1 LASTPIN (-6700 2225) BN 1
J 0
(-6752 2233);
DISPLAY 0.489362 (-6752 2233);
PAINT MONO (-6752 2233);
FORCEPROP 2 LAST CDS_LIB mstr_standard
J 0
(-6750 2225);
DISPLAY INVISIBLE (-6750 2225);
FORCEPROP 1 LAST BODY_TYPE PLUMBING
J 0
(-6750 2175);
DISPLAY 0.574468 (-6750 2175);
PAINT GREEN (-6750 2175);
DISPLAY INVISIBLE (-6750 2175);
FORCEPROP 1 LAST HDL_TAP TRUE
J 0
(-6425 2100);
DISPLAY 0.574468 (-6425 2100);
PAINT GREEN (-6425 2100);
DISPLAY INVISIBLE (-6425 2100);
FORCEPROP 1 LAST PATH I323
J 0
(-6752 2225);
DISPLAY 0.872340 (-6752 2225);
PAINT GREEN (-6752 2225);
DISPLAY INVISIBLE (-6752 2225);
FORCEADD TAP..6
(-6900 2275);
FORCEPROP 3 LASTPIN (-6850 2275) SIG_NAME P5E_CPU0_P1_RX_DN<0>
J 0
(-6840 2285);
DISPLAY 0.659574 (-6840 2285);
PAINT MONO (-6840 2285);
DISPLAY INVISIBLE (-6840 2285);
FORCEPROP 1 LASTPIN (-6850 2275) BN 0
J 0
(-6902 2283);
DISPLAY 0.489362 (-6902 2283);
PAINT MONO (-6902 2283);
FORCEPROP 2 LAST CDS_LIB mstr_standard
J 0
(-6900 2275);
DISPLAY INVISIBLE (-6900 2275);
FORCEPROP 1 LAST BODY_TYPE PLUMBING
J 0
(-6900 2225);
DISPLAY 0.574468 (-6900 2225);
PAINT GREEN (-6900 2225);
DISPLAY INVISIBLE (-6900 2225);
FORCEPROP 1 LAST HDL_TAP TRUE
J 0
(-6575 2150);
DISPLAY 0.574468 (-6575 2150);
PAINT GREEN (-6575 2150);
DISPLAY INVISIBLE (-6575 2150);
FORCEPROP 1 LAST PATH I324
J 0
(-6902 2275);
DISPLAY 0.872340 (-6902 2275);
PAINT GREEN (-6902 2275);
DISPLAY INVISIBLE (-6902 2275);
FORCEADD TAP..6
(-6750 2325);
FORCEPROP 3 LASTPIN (-6700 2325) SIG_NAME P5E_CPU0_P1_RX_DP<0>
J 0
(-6690 2335);
DISPLAY 0.659574 (-6690 2335);
PAINT MONO (-6690 2335);
DISPLAY INVISIBLE (-6690 2335);
FORCEPROP 1 LASTPIN (-6700 2325) BN 0
J 0
(-6752 2333);
DISPLAY 0.489362 (-6752 2333);
PAINT MONO (-6752 2333);
FORCEPROP 2 LAST CDS_LIB mstr_standard
J 0
(-6750 2325);
DISPLAY INVISIBLE (-6750 2325);
FORCEPROP 1 LAST BODY_TYPE PLUMBING
J 0
(-6750 2275);
DISPLAY 0.574468 (-6750 2275);
PAINT GREEN (-6750 2275);
DISPLAY INVISIBLE (-6750 2275);
FORCEPROP 1 LAST HDL_TAP TRUE
J 0
(-6425 2200);
DISPLAY 0.574468 (-6425 2200);
PAINT GREEN (-6425 2200);
DISPLAY INVISIBLE (-6425 2200);
FORCEPROP 1 LAST PATH I325
J 0
(-6752 2325);
DISPLAY 0.872340 (-6752 2325);
PAINT GREEN (-6752 2325);
DISPLAY INVISIBLE (-6752 2325);
FORCEADD TAP..6
(-6825 4450);
FORCEPROP 3 LASTPIN (-6775 4450) SIG_NAME P5E_CPU0_P0_RX_DN<13>
J 0
(-6765 4460);
DISPLAY 0.659574 (-6765 4460);
PAINT MONO (-6765 4460);
DISPLAY INVISIBLE (-6765 4460);
FORCEPROP 1 LASTPIN (-6775 4450) BN 13
J 0
(-6827 4458);
DISPLAY 0.680851 (-6827 4458);
PAINT MONO (-6827 4458);
FORCEPROP 2 LAST CDS_LIB standard
J 0
(-6825 4450);
DISPLAY INVISIBLE (-6825 4450);
FORCEPROP 1 LAST BODY_TYPE PLUMBING
J 0
(-6825 4400);
DISPLAY 0.574468 (-6825 4400);
PAINT GREEN (-6825 4400);
DISPLAY INVISIBLE (-6825 4400);
FORCEPROP 1 LAST HDL_TAP TRUE
J 0
(-6500 4325);
DISPLAY 0.574468 (-6500 4325);
PAINT GREEN (-6500 4325);
DISPLAY INVISIBLE (-6500 4325);
FORCEPROP 1 LAST PATH I326
J 0
(-6827 4450);
DISPLAY 0.872340 (-6827 4450);
PAINT GREEN (-6827 4450);
DISPLAY INVISIBLE (-6827 4450);
FORCEADD TAP..6
(-6675 4300);
FORCEPROP 3 LASTPIN (-6625 4300) SIG_NAME P5E_CPU0_P0_RX_DP<15>
J 0
(-6615 4310);
DISPLAY 0.659574 (-6615 4310);
PAINT MONO (-6615 4310);
DISPLAY INVISIBLE (-6615 4310);
FORCEPROP 1 LASTPIN (-6625 4300) BN 15
J 0
(-6677 4308);
DISPLAY 0.680851 (-6677 4308);
PAINT MONO (-6677 4308);
FORCEPROP 2 LAST CDS_LIB standard
J 0
(-6675 4300);
DISPLAY INVISIBLE (-6675 4300);
FORCEPROP 1 LAST BODY_TYPE PLUMBING
J 0
(-6675 4250);
DISPLAY 0.574468 (-6675 4250);
PAINT GREEN (-6675 4250);
DISPLAY INVISIBLE (-6675 4250);
FORCEPROP 1 LAST HDL_TAP TRUE
J 0
(-6350 4175);
DISPLAY 0.574468 (-6350 4175);
PAINT GREEN (-6350 4175);
DISPLAY INVISIBLE (-6350 4175);
FORCEPROP 1 LAST PATH I327
J 0
(-6677 4300);
DISPLAY 0.872340 (-6677 4300);
PAINT GREEN (-6677 4300);
DISPLAY INVISIBLE (-6677 4300);
FORCEADD TAP..6
(-6675 5800);
FORCEPROP 3 LASTPIN (-6625 5800) SIG_NAME P5E_CPU0_P0_RX_DP<0>
J 0
(-6615 5810);
DISPLAY 0.659574 (-6615 5810);
PAINT MONO (-6615 5810);
DISPLAY INVISIBLE (-6615 5810);
FORCEPROP 1 LASTPIN (-6625 5800) BN 0
J 0
(-6677 5808);
DISPLAY 0.680851 (-6677 5808);
PAINT MONO (-6677 5808);
FORCEPROP 2 LAST CDS_LIB mstr_standard
J 0
(-6675 5800);
DISPLAY INVISIBLE (-6675 5800);
FORCEPROP 1 LAST BODY_TYPE PLUMBING
J 0
(-6675 5750);
DISPLAY 0.574468 (-6675 5750);
PAINT GREEN (-6675 5750);
DISPLAY INVISIBLE (-6675 5750);
FORCEPROP 1 LAST HDL_TAP TRUE
J 0
(-6350 5675);
DISPLAY 0.574468 (-6350 5675);
PAINT GREEN (-6350 5675);
DISPLAY INVISIBLE (-6350 5675);
FORCEPROP 1 LAST PATH I328
J 0
(-6677 5800);
DISPLAY 0.872340 (-6677 5800);
PAINT GREEN (-6677 5800);
DISPLAY INVISIBLE (-6677 5800);
FORCEADD TAP..6
(-6675 5700);
FORCEPROP 3 LASTPIN (-6625 5700) SIG_NAME P5E_CPU0_P0_RX_DP<1>
J 0
(-6615 5710);
DISPLAY 0.659574 (-6615 5710);
PAINT MONO (-6615 5710);
DISPLAY INVISIBLE (-6615 5710);
FORCEPROP 1 LASTPIN (-6625 5700) BN 1
J 0
(-6677 5708);
DISPLAY 0.680851 (-6677 5708);
PAINT MONO (-6677 5708);
FORCEPROP 2 LAST CDS_LIB mstr_standard
J 0
(-6675 5700);
DISPLAY INVISIBLE (-6675 5700);
FORCEPROP 1 LAST BODY_TYPE PLUMBING
J 0
(-6675 5650);
DISPLAY 0.574468 (-6675 5650);
PAINT GREEN (-6675 5650);
DISPLAY INVISIBLE (-6675 5650);
FORCEPROP 1 LAST HDL_TAP TRUE
J 0
(-6350 5575);
DISPLAY 0.574468 (-6350 5575);
PAINT GREEN (-6350 5575);
DISPLAY INVISIBLE (-6350 5575);
FORCEPROP 1 LAST PATH I329
J 0
(-6677 5700);
DISPLAY 0.872340 (-6677 5700);
PAINT GREEN (-6677 5700);
DISPLAY INVISIBLE (-6677 5700);
FORCEADD TAP..6
(-6675 5600);
FORCEPROP 3 LASTPIN (-6625 5600) SIG_NAME P5E_CPU0_P0_RX_DP<2>
J 0
(-6615 5610);
DISPLAY 0.659574 (-6615 5610);
PAINT MONO (-6615 5610);
DISPLAY INVISIBLE (-6615 5610);
FORCEPROP 1 LASTPIN (-6625 5600) BN 2
J 0
(-6677 5608);
DISPLAY 0.680851 (-6677 5608);
PAINT MONO (-6677 5608);
FORCEPROP 2 LAST CDS_LIB mstr_standard
J 0
(-6675 5600);
DISPLAY INVISIBLE (-6675 5600);
FORCEPROP 1 LAST BODY_TYPE PLUMBING
J 0
(-6675 5550);
DISPLAY 0.574468 (-6675 5550);
PAINT GREEN (-6675 5550);
DISPLAY INVISIBLE (-6675 5550);
FORCEPROP 1 LAST HDL_TAP TRUE
J 0
(-6350 5475);
DISPLAY 0.574468 (-6350 5475);
PAINT GREEN (-6350 5475);
DISPLAY INVISIBLE (-6350 5475);
FORCEPROP 1 LAST PATH I330
J 0
(-6677 5600);
DISPLAY 0.872340 (-6677 5600);
PAINT GREEN (-6677 5600);
DISPLAY INVISIBLE (-6677 5600);
FORCEADD TAP..6
(-6825 5550);
FORCEPROP 3 LASTPIN (-6775 5550) SIG_NAME P5E_CPU0_P0_RX_DN<2>
J 0
(-6765 5560);
DISPLAY 0.659574 (-6765 5560);
PAINT MONO (-6765 5560);
DISPLAY INVISIBLE (-6765 5560);
FORCEPROP 1 LASTPIN (-6775 5550) BN 2
J 0
(-6827 5558);
DISPLAY 0.680851 (-6827 5558);
PAINT MONO (-6827 5558);
FORCEPROP 2 LAST CDS_LIB standard
J 0
(-6825 5550);
DISPLAY INVISIBLE (-6825 5550);
FORCEPROP 1 LAST BODY_TYPE PLUMBING
J 0
(-6825 5500);
DISPLAY 0.574468 (-6825 5500);
PAINT GREEN (-6825 5500);
DISPLAY INVISIBLE (-6825 5500);
FORCEPROP 1 LAST HDL_TAP TRUE
J 0
(-6500 5425);
DISPLAY 0.574468 (-6500 5425);
PAINT GREEN (-6500 5425);
DISPLAY INVISIBLE (-6500 5425);
FORCEPROP 1 LAST PATH I331
J 0
(-6827 5550);
DISPLAY 0.872340 (-6827 5550);
PAINT GREEN (-6827 5550);
DISPLAY INVISIBLE (-6827 5550);
FORCEADD TAP..6
(-6825 5650);
FORCEPROP 3 LASTPIN (-6775 5650) SIG_NAME P5E_CPU0_P0_RX_DN<1>
J 0
(-6765 5660);
DISPLAY 0.659574 (-6765 5660);
PAINT MONO (-6765 5660);
DISPLAY INVISIBLE (-6765 5660);
FORCEPROP 1 LASTPIN (-6775 5650) BN 1
J 0
(-6827 5658);
DISPLAY 0.680851 (-6827 5658);
PAINT MONO (-6827 5658);
FORCEPROP 2 LAST CDS_LIB mstr_standard
J 0
(-6825 5650);
DISPLAY INVISIBLE (-6825 5650);
FORCEPROP 1 LAST BODY_TYPE PLUMBING
J 0
(-6825 5600);
DISPLAY 0.574468 (-6825 5600);
PAINT GREEN (-6825 5600);
DISPLAY INVISIBLE (-6825 5600);
FORCEPROP 1 LAST HDL_TAP TRUE
J 0
(-6500 5525);
DISPLAY 0.574468 (-6500 5525);
PAINT GREEN (-6500 5525);
DISPLAY INVISIBLE (-6500 5525);
FORCEPROP 1 LAST PATH I332
J 0
(-6827 5650);
DISPLAY 0.872340 (-6827 5650);
PAINT GREEN (-6827 5650);
DISPLAY INVISIBLE (-6827 5650);
FORCEADD TAP..6
(-6825 5750);
FORCEPROP 3 LASTPIN (-6775 5750) SIG_NAME P5E_CPU0_P0_RX_DN<0>
J 0
(-6765 5760);
DISPLAY 0.659574 (-6765 5760);
PAINT MONO (-6765 5760);
DISPLAY INVISIBLE (-6765 5760);
FORCEPROP 1 LASTPIN (-6775 5750) BN 0
J 0
(-6827 5758);
DISPLAY 0.680851 (-6827 5758);
PAINT MONO (-6827 5758);
FORCEPROP 2 LAST CDS_LIB mstr_standard
J 0
(-6825 5750);
DISPLAY INVISIBLE (-6825 5750);
FORCEPROP 1 LAST BODY_TYPE PLUMBING
J 0
(-6825 5700);
DISPLAY 0.574468 (-6825 5700);
PAINT GREEN (-6825 5700);
DISPLAY INVISIBLE (-6825 5700);
FORCEPROP 1 LAST HDL_TAP TRUE
J 0
(-6500 5625);
DISPLAY 0.574468 (-6500 5625);
PAINT GREEN (-6500 5625);
DISPLAY INVISIBLE (-6500 5625);
FORCEPROP 1 LAST PATH I333
J 0
(-6827 5750);
DISPLAY 0.872340 (-6827 5750);
PAINT GREEN (-6827 5750);
DISPLAY INVISIBLE (-6827 5750);
FORCEADD TAP..6
(-6675 5500);
FORCEPROP 3 LASTPIN (-6625 5500) SIG_NAME P5E_CPU0_P0_RX_DP<3>
J 0
(-6615 5510);
DISPLAY 0.659574 (-6615 5510);
PAINT MONO (-6615 5510);
DISPLAY INVISIBLE (-6615 5510);
FORCEPROP 1 LASTPIN (-6625 5500) BN 3
J 0
(-6677 5508);
DISPLAY 0.680851 (-6677 5508);
PAINT MONO (-6677 5508);
FORCEPROP 2 LAST CDS_LIB standard
J 0
(-6675 5500);
DISPLAY INVISIBLE (-6675 5500);
FORCEPROP 1 LAST BODY_TYPE PLUMBING
J 0
(-6675 5450);
DISPLAY 0.574468 (-6675 5450);
PAINT GREEN (-6675 5450);
DISPLAY INVISIBLE (-6675 5450);
FORCEPROP 1 LAST HDL_TAP TRUE
J 0
(-6350 5375);
DISPLAY 0.574468 (-6350 5375);
PAINT GREEN (-6350 5375);
DISPLAY INVISIBLE (-6350 5375);
FORCEPROP 1 LAST PATH I334
J 0
(-6677 5500);
DISPLAY 0.872340 (-6677 5500);
PAINT GREEN (-6677 5500);
DISPLAY INVISIBLE (-6677 5500);
FORCEADD TAP..6
(-6675 5400);
FORCEPROP 3 LASTPIN (-6625 5400) SIG_NAME P5E_CPU0_P0_RX_DP<4>
J 0
(-6615 5410);
DISPLAY 0.659574 (-6615 5410);
PAINT MONO (-6615 5410);
DISPLAY INVISIBLE (-6615 5410);
FORCEPROP 1 LASTPIN (-6625 5400) BN 4
J 0
(-6677 5408);
DISPLAY 0.680851 (-6677 5408);
PAINT MONO (-6677 5408);
FORCEPROP 2 LAST CDS_LIB standard
J 0
(-6675 5400);
DISPLAY INVISIBLE (-6675 5400);
FORCEPROP 1 LAST BODY_TYPE PLUMBING
J 0
(-6675 5350);
DISPLAY 0.574468 (-6675 5350);
PAINT GREEN (-6675 5350);
DISPLAY INVISIBLE (-6675 5350);
FORCEPROP 1 LAST HDL_TAP TRUE
J 0
(-6350 5275);
DISPLAY 0.574468 (-6350 5275);
PAINT GREEN (-6350 5275);
DISPLAY INVISIBLE (-6350 5275);
FORCEPROP 1 LAST PATH I335
J 0
(-6677 5400);
DISPLAY 0.872340 (-6677 5400);
PAINT GREEN (-6677 5400);
DISPLAY INVISIBLE (-6677 5400);
FORCEADD TAP..6
(-6675 5300);
FORCEPROP 3 LASTPIN (-6625 5300) SIG_NAME P5E_CPU0_P0_RX_DP<5>
J 0
(-6615 5310);
DISPLAY 0.659574 (-6615 5310);
PAINT MONO (-6615 5310);
DISPLAY INVISIBLE (-6615 5310);
FORCEPROP 1 LASTPIN (-6625 5300) BN 5
J 0
(-6677 5308);
DISPLAY 0.680851 (-6677 5308);
PAINT MONO (-6677 5308);
FORCEPROP 2 LAST CDS_LIB standard
J 0
(-6675 5300);
DISPLAY INVISIBLE (-6675 5300);
FORCEPROP 1 LAST BODY_TYPE PLUMBING
J 0
(-6675 5250);
DISPLAY 0.574468 (-6675 5250);
PAINT GREEN (-6675 5250);
DISPLAY INVISIBLE (-6675 5250);
FORCEPROP 1 LAST HDL_TAP TRUE
J 0
(-6350 5175);
DISPLAY 0.574468 (-6350 5175);
PAINT GREEN (-6350 5175);
DISPLAY INVISIBLE (-6350 5175);
FORCEPROP 1 LAST PATH I336
J 0
(-6677 5300);
DISPLAY 0.872340 (-6677 5300);
PAINT GREEN (-6677 5300);
DISPLAY INVISIBLE (-6677 5300);
FORCEADD TAP..6
(-6675 5200);
FORCEPROP 3 LASTPIN (-6625 5200) SIG_NAME P5E_CPU0_P0_RX_DP<6>
J 0
(-6615 5210);
DISPLAY 0.659574 (-6615 5210);
PAINT MONO (-6615 5210);
DISPLAY INVISIBLE (-6615 5210);
FORCEPROP 1 LASTPIN (-6625 5200) BN 6
J 0
(-6677 5208);
DISPLAY 0.680851 (-6677 5208);
PAINT MONO (-6677 5208);
FORCEPROP 2 LAST CDS_LIB standard
J 0
(-6675 5200);
DISPLAY INVISIBLE (-6675 5200);
FORCEPROP 1 LAST BODY_TYPE PLUMBING
J 0
(-6675 5150);
DISPLAY 0.574468 (-6675 5150);
PAINT GREEN (-6675 5150);
DISPLAY INVISIBLE (-6675 5150);
FORCEPROP 1 LAST HDL_TAP TRUE
J 0
(-6350 5075);
DISPLAY 0.574468 (-6350 5075);
PAINT GREEN (-6350 5075);
DISPLAY INVISIBLE (-6350 5075);
FORCEPROP 1 LAST PATH I337
J 0
(-6677 5200);
DISPLAY 0.872340 (-6677 5200);
PAINT GREEN (-6677 5200);
DISPLAY INVISIBLE (-6677 5200);
FORCEADD TAP..6
(-6675 5100);
FORCEPROP 3 LASTPIN (-6625 5100) SIG_NAME P5E_CPU0_P0_RX_DP<7>
J 0
(-6615 5110);
DISPLAY 0.659574 (-6615 5110);
PAINT MONO (-6615 5110);
DISPLAY INVISIBLE (-6615 5110);
FORCEPROP 1 LASTPIN (-6625 5100) BN 7
J 0
(-6677 5108);
DISPLAY 0.680851 (-6677 5108);
PAINT MONO (-6677 5108);
FORCEPROP 2 LAST CDS_LIB standard
J 0
(-6675 5100);
DISPLAY INVISIBLE (-6675 5100);
FORCEPROP 1 LAST BODY_TYPE PLUMBING
J 0
(-6675 5050);
DISPLAY 0.574468 (-6675 5050);
PAINT GREEN (-6675 5050);
DISPLAY INVISIBLE (-6675 5050);
FORCEPROP 1 LAST HDL_TAP TRUE
J 0
(-6350 4975);
DISPLAY 0.574468 (-6350 4975);
PAINT GREEN (-6350 4975);
DISPLAY INVISIBLE (-6350 4975);
FORCEPROP 1 LAST PATH I338
J 0
(-6677 5100);
DISPLAY 0.872340 (-6677 5100);
PAINT GREEN (-6677 5100);
DISPLAY INVISIBLE (-6677 5100);
FORCEADD TAP..6
(-6825 5350);
FORCEPROP 3 LASTPIN (-6775 5350) SIG_NAME P5E_CPU0_P0_RX_DN<4>
J 0
(-6765 5360);
DISPLAY 0.659574 (-6765 5360);
PAINT MONO (-6765 5360);
DISPLAY INVISIBLE (-6765 5360);
FORCEPROP 1 LASTPIN (-6775 5350) BN 4
J 0
(-6827 5358);
DISPLAY 0.680851 (-6827 5358);
PAINT MONO (-6827 5358);
FORCEPROP 2 LAST CDS_LIB standard
J 0
(-6825 5350);
DISPLAY INVISIBLE (-6825 5350);
FORCEPROP 1 LAST BODY_TYPE PLUMBING
J 0
(-6825 5300);
DISPLAY 0.574468 (-6825 5300);
PAINT GREEN (-6825 5300);
DISPLAY INVISIBLE (-6825 5300);
FORCEPROP 1 LAST HDL_TAP TRUE
J 0
(-6500 5225);
DISPLAY 0.574468 (-6500 5225);
PAINT GREEN (-6500 5225);
DISPLAY INVISIBLE (-6500 5225);
FORCEPROP 1 LAST PATH I339
J 0
(-6827 5350);
DISPLAY 0.872340 (-6827 5350);
PAINT GREEN (-6827 5350);
DISPLAY INVISIBLE (-6827 5350);
FORCEADD TAP..6
(-6825 5450);
FORCEPROP 3 LASTPIN (-6775 5450) SIG_NAME P5E_CPU0_P0_RX_DN<3>
J 0
(-6765 5460);
DISPLAY 0.659574 (-6765 5460);
PAINT MONO (-6765 5460);
DISPLAY INVISIBLE (-6765 5460);
FORCEPROP 1 LASTPIN (-6775 5450) BN 3
J 0
(-6827 5458);
DISPLAY 0.680851 (-6827 5458);
PAINT MONO (-6827 5458);
FORCEPROP 2 LAST CDS_LIB standard
J 0
(-6825 5450);
DISPLAY INVISIBLE (-6825 5450);
FORCEPROP 1 LAST BODY_TYPE PLUMBING
J 0
(-6825 5400);
DISPLAY 0.574468 (-6825 5400);
PAINT GREEN (-6825 5400);
DISPLAY INVISIBLE (-6825 5400);
FORCEPROP 1 LAST HDL_TAP TRUE
J 0
(-6500 5325);
DISPLAY 0.574468 (-6500 5325);
PAINT GREEN (-6500 5325);
DISPLAY INVISIBLE (-6500 5325);
FORCEPROP 1 LAST PATH I340
J 0
(-6827 5450);
DISPLAY 0.872340 (-6827 5450);
PAINT GREEN (-6827 5450);
DISPLAY INVISIBLE (-6827 5450);
FORCEADD TAP..6
(-6825 5250);
FORCEPROP 3 LASTPIN (-6775 5250) SIG_NAME P5E_CPU0_P0_RX_DN<5>
J 0
(-6765 5260);
DISPLAY 0.659574 (-6765 5260);
PAINT MONO (-6765 5260);
DISPLAY INVISIBLE (-6765 5260);
FORCEPROP 1 LASTPIN (-6775 5250) BN 5
J 0
(-6827 5258);
DISPLAY 0.680851 (-6827 5258);
PAINT MONO (-6827 5258);
FORCEPROP 2 LAST CDS_LIB standard
J 0
(-6825 5250);
DISPLAY INVISIBLE (-6825 5250);
FORCEPROP 1 LAST BODY_TYPE PLUMBING
J 0
(-6825 5200);
DISPLAY 0.574468 (-6825 5200);
PAINT GREEN (-6825 5200);
DISPLAY INVISIBLE (-6825 5200);
FORCEPROP 1 LAST HDL_TAP TRUE
J 0
(-6500 5125);
DISPLAY 0.574468 (-6500 5125);
PAINT GREEN (-6500 5125);
DISPLAY INVISIBLE (-6500 5125);
FORCEPROP 1 LAST PATH I341
J 0
(-6827 5250);
DISPLAY 0.872340 (-6827 5250);
PAINT GREEN (-6827 5250);
DISPLAY INVISIBLE (-6827 5250);
FORCEADD TAP..6
(-6825 5150);
FORCEPROP 3 LASTPIN (-6775 5150) SIG_NAME P5E_CPU0_P0_RX_DN<6>
J 0
(-6765 5160);
DISPLAY 0.659574 (-6765 5160);
PAINT MONO (-6765 5160);
DISPLAY INVISIBLE (-6765 5160);
FORCEPROP 1 LASTPIN (-6775 5150) BN 6
J 0
(-6827 5158);
DISPLAY 0.680851 (-6827 5158);
PAINT MONO (-6827 5158);
FORCEPROP 2 LAST CDS_LIB standard
J 0
(-6825 5150);
DISPLAY INVISIBLE (-6825 5150);
FORCEPROP 1 LAST BODY_TYPE PLUMBING
J 0
(-6825 5100);
DISPLAY 0.574468 (-6825 5100);
PAINT GREEN (-6825 5100);
DISPLAY INVISIBLE (-6825 5100);
FORCEPROP 1 LAST HDL_TAP TRUE
J 0
(-6500 5025);
DISPLAY 0.574468 (-6500 5025);
PAINT GREEN (-6500 5025);
DISPLAY INVISIBLE (-6500 5025);
FORCEPROP 1 LAST PATH I342
J 0
(-6827 5150);
DISPLAY 0.872340 (-6827 5150);
PAINT GREEN (-6827 5150);
DISPLAY INVISIBLE (-6827 5150);
FORCEADD TAP..6
(-6825 5050);
FORCEPROP 3 LASTPIN (-6775 5050) SIG_NAME P5E_CPU0_P0_RX_DN<7>
J 0
(-6765 5060);
DISPLAY 0.659574 (-6765 5060);
PAINT MONO (-6765 5060);
DISPLAY INVISIBLE (-6765 5060);
FORCEPROP 1 LASTPIN (-6775 5050) BN 7
J 0
(-6827 5058);
DISPLAY 0.680851 (-6827 5058);
PAINT MONO (-6827 5058);
FORCEPROP 2 LAST CDS_LIB standard
J 0
(-6825 5050);
DISPLAY INVISIBLE (-6825 5050);
FORCEPROP 1 LAST BODY_TYPE PLUMBING
J 0
(-6825 5000);
DISPLAY 0.574468 (-6825 5000);
PAINT GREEN (-6825 5000);
DISPLAY INVISIBLE (-6825 5000);
FORCEPROP 1 LAST HDL_TAP TRUE
J 0
(-6500 4925);
DISPLAY 0.574468 (-6500 4925);
PAINT GREEN (-6500 4925);
DISPLAY INVISIBLE (-6500 4925);
FORCEPROP 1 LAST PATH I343
J 0
(-6827 5050);
DISPLAY 0.872340 (-6827 5050);
PAINT GREEN (-6827 5050);
DISPLAY INVISIBLE (-6827 5050);
FORCEADD TAP..6
(-6675 5000);
FORCEPROP 3 LASTPIN (-6625 5000) SIG_NAME P5E_CPU0_P0_RX_DP<8>
J 0
(-6615 5010);
DISPLAY 0.659574 (-6615 5010);
PAINT MONO (-6615 5010);
DISPLAY INVISIBLE (-6615 5010);
FORCEPROP 1 LASTPIN (-6625 5000) BN 8
J 0
(-6677 5008);
DISPLAY 0.680851 (-6677 5008);
PAINT MONO (-6677 5008);
FORCEPROP 2 LAST CDS_LIB standard
J 0
(-6675 5000);
DISPLAY INVISIBLE (-6675 5000);
FORCEPROP 1 LAST BODY_TYPE PLUMBING
J 0
(-6675 4950);
DISPLAY 0.574468 (-6675 4950);
PAINT GREEN (-6675 4950);
DISPLAY INVISIBLE (-6675 4950);
FORCEPROP 1 LAST HDL_TAP TRUE
J 0
(-6350 4875);
DISPLAY 0.574468 (-6350 4875);
PAINT GREEN (-6350 4875);
DISPLAY INVISIBLE (-6350 4875);
FORCEPROP 1 LAST PATH I344
J 0
(-6677 5000);
DISPLAY 0.872340 (-6677 5000);
PAINT GREEN (-6677 5000);
DISPLAY INVISIBLE (-6677 5000);
FORCEADD TAP..6
(-6675 4900);
FORCEPROP 3 LASTPIN (-6625 4900) SIG_NAME P5E_CPU0_P0_RX_DP<9>
J 0
(-6615 4910);
DISPLAY 0.659574 (-6615 4910);
PAINT MONO (-6615 4910);
DISPLAY INVISIBLE (-6615 4910);
FORCEPROP 1 LASTPIN (-6625 4900) BN 9
J 0
(-6677 4908);
DISPLAY 0.680851 (-6677 4908);
PAINT MONO (-6677 4908);
FORCEPROP 2 LAST CDS_LIB standard
J 0
(-6675 4900);
DISPLAY INVISIBLE (-6675 4900);
FORCEPROP 1 LAST BODY_TYPE PLUMBING
J 0
(-6675 4850);
DISPLAY 0.574468 (-6675 4850);
PAINT GREEN (-6675 4850);
DISPLAY INVISIBLE (-6675 4850);
FORCEPROP 1 LAST HDL_TAP TRUE
J 0
(-6350 4775);
DISPLAY 0.574468 (-6350 4775);
PAINT GREEN (-6350 4775);
DISPLAY INVISIBLE (-6350 4775);
FORCEPROP 1 LAST PATH I345
J 0
(-6677 4900);
DISPLAY 0.872340 (-6677 4900);
PAINT GREEN (-6677 4900);
DISPLAY INVISIBLE (-6677 4900);
FORCEADD TAP..6
(-6675 4800);
FORCEPROP 3 LASTPIN (-6625 4800) SIG_NAME P5E_CPU0_P0_RX_DP<10>
J 0
(-6615 4810);
DISPLAY 0.659574 (-6615 4810);
PAINT MONO (-6615 4810);
DISPLAY INVISIBLE (-6615 4810);
FORCEPROP 1 LASTPIN (-6625 4800) BN 10
J 0
(-6677 4808);
DISPLAY 0.680851 (-6677 4808);
PAINT MONO (-6677 4808);
FORCEPROP 2 LAST CDS_LIB standard
J 0
(-6675 4800);
DISPLAY INVISIBLE (-6675 4800);
FORCEPROP 1 LAST BODY_TYPE PLUMBING
J 0
(-6675 4750);
DISPLAY 0.574468 (-6675 4750);
PAINT GREEN (-6675 4750);
DISPLAY INVISIBLE (-6675 4750);
FORCEPROP 1 LAST HDL_TAP TRUE
J 0
(-6350 4675);
DISPLAY 0.574468 (-6350 4675);
PAINT GREEN (-6350 4675);
DISPLAY INVISIBLE (-6350 4675);
FORCEPROP 1 LAST PATH I346
J 0
(-6677 4800);
DISPLAY 0.872340 (-6677 4800);
PAINT GREEN (-6677 4800);
DISPLAY INVISIBLE (-6677 4800);
FORCEADD TAP..6
(-6675 4700);
FORCEPROP 3 LASTPIN (-6625 4700) SIG_NAME P5E_CPU0_P0_RX_DP<11>
J 0
(-6615 4710);
DISPLAY 0.659574 (-6615 4710);
PAINT MONO (-6615 4710);
DISPLAY INVISIBLE (-6615 4710);
FORCEPROP 1 LASTPIN (-6625 4700) BN 11
J 0
(-6677 4708);
DISPLAY 0.680851 (-6677 4708);
PAINT MONO (-6677 4708);
FORCEPROP 2 LAST CDS_LIB standard
J 0
(-6675 4700);
DISPLAY INVISIBLE (-6675 4700);
FORCEPROP 1 LAST BODY_TYPE PLUMBING
J 0
(-6675 4650);
DISPLAY 0.574468 (-6675 4650);
PAINT GREEN (-6675 4650);
DISPLAY INVISIBLE (-6675 4650);
FORCEPROP 1 LAST HDL_TAP TRUE
J 0
(-6350 4575);
DISPLAY 0.574468 (-6350 4575);
PAINT GREEN (-6350 4575);
DISPLAY INVISIBLE (-6350 4575);
FORCEPROP 1 LAST PATH I347
J 0
(-6677 4700);
DISPLAY 0.872340 (-6677 4700);
PAINT GREEN (-6677 4700);
DISPLAY INVISIBLE (-6677 4700);
FORCEADD TAP..6
(-6675 4500);
FORCEPROP 3 LASTPIN (-6625 4500) SIG_NAME P5E_CPU0_P0_RX_DP<13>
J 0
(-6615 4510);
DISPLAY 0.659574 (-6615 4510);
PAINT MONO (-6615 4510);
DISPLAY INVISIBLE (-6615 4510);
FORCEPROP 1 LASTPIN (-6625 4500) BN 13
J 0
(-6677 4508);
DISPLAY 0.680851 (-6677 4508);
PAINT MONO (-6677 4508);
FORCEPROP 2 LAST CDS_LIB standard
J 0
(-6675 4500);
DISPLAY INVISIBLE (-6675 4500);
FORCEPROP 1 LAST BODY_TYPE PLUMBING
J 0
(-6675 4450);
DISPLAY 0.574468 (-6675 4450);
PAINT GREEN (-6675 4450);
DISPLAY INVISIBLE (-6675 4450);
FORCEPROP 1 LAST HDL_TAP TRUE
J 0
(-6350 4375);
DISPLAY 0.574468 (-6350 4375);
PAINT GREEN (-6350 4375);
DISPLAY INVISIBLE (-6350 4375);
FORCEPROP 1 LAST PATH I348
J 0
(-6677 4500);
DISPLAY 0.872340 (-6677 4500);
PAINT GREEN (-6677 4500);
DISPLAY INVISIBLE (-6677 4500);
FORCEADD TAP..6
(-6675 4600);
FORCEPROP 3 LASTPIN (-6625 4600) SIG_NAME P5E_CPU0_P0_RX_DP<12>
J 0
(-6615 4610);
DISPLAY 0.659574 (-6615 4610);
PAINT MONO (-6615 4610);
DISPLAY INVISIBLE (-6615 4610);
FORCEPROP 1 LASTPIN (-6625 4600) BN 12
J 0
(-6677 4608);
DISPLAY 0.680851 (-6677 4608);
PAINT MONO (-6677 4608);
FORCEPROP 2 LAST CDS_LIB standard
J 0
(-6675 4600);
DISPLAY INVISIBLE (-6675 4600);
FORCEPROP 1 LAST BODY_TYPE PLUMBING
J 0
(-6675 4550);
DISPLAY 0.574468 (-6675 4550);
PAINT GREEN (-6675 4550);
DISPLAY INVISIBLE (-6675 4550);
FORCEPROP 1 LAST HDL_TAP TRUE
J 0
(-6350 4475);
DISPLAY 0.574468 (-6350 4475);
PAINT GREEN (-6350 4475);
DISPLAY INVISIBLE (-6350 4475);
FORCEPROP 1 LAST PATH I349
J 0
(-6677 4600);
DISPLAY 0.872340 (-6677 4600);
PAINT GREEN (-6677 4600);
DISPLAY INVISIBLE (-6677 4600);
FORCEADD TAP..6
(-6825 4950);
FORCEPROP 3 LASTPIN (-6775 4950) SIG_NAME P5E_CPU0_P0_RX_DN<8>
J 0
(-6765 4960);
DISPLAY 0.659574 (-6765 4960);
PAINT MONO (-6765 4960);
DISPLAY INVISIBLE (-6765 4960);
FORCEPROP 1 LASTPIN (-6775 4950) BN 8
J 0
(-6827 4958);
DISPLAY 0.680851 (-6827 4958);
PAINT MONO (-6827 4958);
FORCEPROP 2 LAST CDS_LIB standard
J 0
(-6825 4950);
DISPLAY INVISIBLE (-6825 4950);
FORCEPROP 1 LAST BODY_TYPE PLUMBING
J 0
(-6825 4900);
DISPLAY 0.574468 (-6825 4900);
PAINT GREEN (-6825 4900);
DISPLAY INVISIBLE (-6825 4900);
FORCEPROP 1 LAST HDL_TAP TRUE
J 0
(-6500 4825);
DISPLAY 0.574468 (-6500 4825);
PAINT GREEN (-6500 4825);
DISPLAY INVISIBLE (-6500 4825);
FORCEPROP 1 LAST PATH I350
J 0
(-6827 4950);
DISPLAY 0.872340 (-6827 4950);
PAINT GREEN (-6827 4950);
DISPLAY INVISIBLE (-6827 4950);
FORCEADD TAP..6
(-6825 4850);
FORCEPROP 3 LASTPIN (-6775 4850) SIG_NAME P5E_CPU0_P0_RX_DN<9>
J 0
(-6765 4860);
DISPLAY 0.659574 (-6765 4860);
PAINT MONO (-6765 4860);
DISPLAY INVISIBLE (-6765 4860);
FORCEPROP 1 LASTPIN (-6775 4850) BN 9
J 0
(-6827 4858);
DISPLAY 0.680851 (-6827 4858);
PAINT MONO (-6827 4858);
FORCEPROP 2 LAST CDS_LIB standard
J 0
(-6825 4850);
DISPLAY INVISIBLE (-6825 4850);
FORCEPROP 1 LAST BODY_TYPE PLUMBING
J 0
(-6825 4800);
DISPLAY 0.574468 (-6825 4800);
PAINT GREEN (-6825 4800);
DISPLAY INVISIBLE (-6825 4800);
FORCEPROP 1 LAST HDL_TAP TRUE
J 0
(-6500 4725);
DISPLAY 0.574468 (-6500 4725);
PAINT GREEN (-6500 4725);
DISPLAY INVISIBLE (-6500 4725);
FORCEPROP 1 LAST PATH I351
J 0
(-6827 4850);
DISPLAY 0.872340 (-6827 4850);
PAINT GREEN (-6827 4850);
DISPLAY INVISIBLE (-6827 4850);
FORCEADD TAP..6
(-6825 4750);
FORCEPROP 3 LASTPIN (-6775 4750) SIG_NAME P5E_CPU0_P0_RX_DN<10>
J 0
(-6765 4760);
DISPLAY 0.659574 (-6765 4760);
PAINT MONO (-6765 4760);
DISPLAY INVISIBLE (-6765 4760);
FORCEPROP 1 LASTPIN (-6775 4750) BN 10
J 0
(-6827 4758);
DISPLAY 0.680851 (-6827 4758);
PAINT MONO (-6827 4758);
FORCEPROP 2 LAST CDS_LIB standard
J 0
(-6825 4750);
DISPLAY INVISIBLE (-6825 4750);
FORCEPROP 1 LAST BODY_TYPE PLUMBING
J 0
(-6825 4700);
DISPLAY 0.574468 (-6825 4700);
PAINT GREEN (-6825 4700);
DISPLAY INVISIBLE (-6825 4700);
FORCEPROP 1 LAST HDL_TAP TRUE
J 0
(-6500 4625);
DISPLAY 0.574468 (-6500 4625);
PAINT GREEN (-6500 4625);
DISPLAY INVISIBLE (-6500 4625);
FORCEPROP 1 LAST PATH I352
J 0
(-6827 4750);
DISPLAY 0.872340 (-6827 4750);
PAINT GREEN (-6827 4750);
DISPLAY INVISIBLE (-6827 4750);
FORCEADD TAP..6
(-6825 4650);
FORCEPROP 3 LASTPIN (-6775 4650) SIG_NAME P5E_CPU0_P0_RX_DN<11>
J 0
(-6765 4660);
DISPLAY 0.659574 (-6765 4660);
PAINT MONO (-6765 4660);
DISPLAY INVISIBLE (-6765 4660);
FORCEPROP 1 LASTPIN (-6775 4650) BN 11
J 0
(-6827 4658);
DISPLAY 0.680851 (-6827 4658);
PAINT MONO (-6827 4658);
FORCEPROP 2 LAST CDS_LIB standard
J 0
(-6825 4650);
DISPLAY INVISIBLE (-6825 4650);
FORCEPROP 1 LAST BODY_TYPE PLUMBING
J 0
(-6825 4600);
DISPLAY 0.574468 (-6825 4600);
PAINT GREEN (-6825 4600);
DISPLAY INVISIBLE (-6825 4600);
FORCEPROP 1 LAST HDL_TAP TRUE
J 0
(-6500 4525);
DISPLAY 0.574468 (-6500 4525);
PAINT GREEN (-6500 4525);
DISPLAY INVISIBLE (-6500 4525);
FORCEPROP 1 LAST PATH I353
J 0
(-6827 4650);
DISPLAY 0.872340 (-6827 4650);
PAINT GREEN (-6827 4650);
DISPLAY INVISIBLE (-6827 4650);
FORCEADD TAP..6
(-6825 4550);
FORCEPROP 3 LASTPIN (-6775 4550) SIG_NAME P5E_CPU0_P0_RX_DN<12>
J 0
(-6765 4560);
DISPLAY 0.659574 (-6765 4560);
PAINT MONO (-6765 4560);
DISPLAY INVISIBLE (-6765 4560);
FORCEPROP 1 LASTPIN (-6775 4550) BN 12
J 0
(-6827 4558);
DISPLAY 0.680851 (-6827 4558);
PAINT MONO (-6827 4558);
FORCEPROP 2 LAST CDS_LIB standard
J 0
(-6825 4550);
DISPLAY INVISIBLE (-6825 4550);
FORCEPROP 1 LAST BODY_TYPE PLUMBING
J 0
(-6825 4500);
DISPLAY 0.574468 (-6825 4500);
PAINT GREEN (-6825 4500);
DISPLAY INVISIBLE (-6825 4500);
FORCEPROP 1 LAST HDL_TAP TRUE
J 0
(-6500 4425);
DISPLAY 0.574468 (-6500 4425);
PAINT GREEN (-6500 4425);
DISPLAY INVISIBLE (-6500 4425);
FORCEPROP 1 LAST PATH I354
J 0
(-6827 4550);
DISPLAY 0.872340 (-6827 4550);
PAINT GREEN (-6827 4550);
DISPLAY INVISIBLE (-6827 4550);
FORCEADD TAP..6
(-6675 4400);
FORCEPROP 3 LASTPIN (-6625 4400) SIG_NAME P5E_CPU0_P0_RX_DP<14>
J 0
(-6615 4410);
DISPLAY 0.659574 (-6615 4410);
PAINT MONO (-6615 4410);
DISPLAY INVISIBLE (-6615 4410);
FORCEPROP 1 LASTPIN (-6625 4400) BN 14
J 0
(-6677 4408);
DISPLAY 0.680851 (-6677 4408);
PAINT MONO (-6677 4408);
FORCEPROP 2 LAST CDS_LIB standard
J 0
(-6675 4400);
DISPLAY INVISIBLE (-6675 4400);
FORCEPROP 1 LAST BODY_TYPE PLUMBING
J 0
(-6675 4350);
DISPLAY 0.574468 (-6675 4350);
PAINT GREEN (-6675 4350);
DISPLAY INVISIBLE (-6675 4350);
FORCEPROP 1 LAST HDL_TAP TRUE
J 0
(-6350 4275);
DISPLAY 0.574468 (-6350 4275);
PAINT GREEN (-6350 4275);
DISPLAY INVISIBLE (-6350 4275);
FORCEPROP 1 LAST PATH I355
J 0
(-6677 4400);
DISPLAY 0.872340 (-6677 4400);
PAINT GREEN (-6677 4400);
DISPLAY INVISIBLE (-6677 4400);
FORCEADD TAP..6
(-6825 4250);
FORCEPROP 3 LASTPIN (-6775 4250) SIG_NAME P5E_CPU0_P0_RX_DN<15>
J 0
(-6765 4260);
DISPLAY 0.659574 (-6765 4260);
PAINT MONO (-6765 4260);
DISPLAY INVISIBLE (-6765 4260);
FORCEPROP 1 LASTPIN (-6775 4250) BN 15
J 0
(-6827 4258);
DISPLAY 0.680851 (-6827 4258);
PAINT MONO (-6827 4258);
FORCEPROP 2 LAST CDS_LIB standard
J 0
(-6825 4250);
DISPLAY INVISIBLE (-6825 4250);
FORCEPROP 1 LAST BODY_TYPE PLUMBING
J 0
(-6825 4200);
DISPLAY 0.574468 (-6825 4200);
PAINT GREEN (-6825 4200);
DISPLAY INVISIBLE (-6825 4200);
FORCEPROP 1 LAST HDL_TAP TRUE
J 0
(-6500 4125);
DISPLAY 0.574468 (-6500 4125);
PAINT GREEN (-6500 4125);
DISPLAY INVISIBLE (-6500 4125);
FORCEPROP 1 LAST PATH I356
J 0
(-6827 4250);
DISPLAY 0.872340 (-6827 4250);
PAINT GREEN (-6827 4250);
DISPLAY INVISIBLE (-6827 4250);
FORCEADD TAP..6
(-6825 4350);
FORCEPROP 3 LASTPIN (-6775 4350) SIG_NAME P5E_CPU0_P0_RX_DN<14>
J 0
(-6765 4360);
DISPLAY 0.659574 (-6765 4360);
PAINT MONO (-6765 4360);
DISPLAY INVISIBLE (-6765 4360);
FORCEPROP 1 LASTPIN (-6775 4350) BN 14
J 0
(-6827 4358);
DISPLAY 0.680851 (-6827 4358);
PAINT MONO (-6827 4358);
FORCEPROP 2 LAST CDS_LIB standard
J 0
(-6825 4350);
DISPLAY INVISIBLE (-6825 4350);
FORCEPROP 1 LAST BODY_TYPE PLUMBING
J 0
(-6825 4300);
DISPLAY 0.574468 (-6825 4300);
PAINT GREEN (-6825 4300);
DISPLAY INVISIBLE (-6825 4300);
FORCEPROP 1 LAST HDL_TAP TRUE
J 0
(-6500 4225);
DISPLAY 0.574468 (-6500 4225);
PAINT GREEN (-6500 4225);
DISPLAY INVISIBLE (-6500 4225);
FORCEPROP 1 LAST PATH I357
J 0
(-6827 4350);
DISPLAY 0.872340 (-6827 4350);
PAINT GREEN (-6827 4350);
DISPLAY INVISIBLE (-6827 4350);
FORCEADD OFFPAGE..1
(-8050 5975);
FORCEPROP 2 LAST $XR0 274 
J 0
(-8302 5975);
DISPLAY 0.638298 (-8302 5975);
PAINT MONO (-8302 5975);
FORCEPROP 2 LAST CDS_LIB standard
J 0
(-8050 5975);
DISPLAY INVISIBLE (-8050 5975);
FORCEPROP 1 LAST OFFPAGE TRUE
J 0
(-7725 5850);
DISPLAY 0.872340 (-7725 5850);
PAINT GREEN (-7725 5850);
DISPLAY INVISIBLE (-7725 5850);
FORCEPROP 1 LAST COMMENT_BODY TRUE
J 0
(-7925 5875);
DISPLAY 0.872340 (-7925 5875);
PAINT GREEN (-7925 5875);
DISPLAY INVISIBLE (-7925 5875);
FORCEPROP 2 LAST PATH I358
J 0
(-8000 6050);
DISPLAY 0.680851 (-8000 6050);
DISPLAY INVISIBLE (-8000 6050);
FORCEADD OFFPAGE..1
(-8050 6025);
FORCEPROP 2 LAST $XR0 274 
J 0
(-8302 6025);
DISPLAY 0.638298 (-8302 6025);
PAINT MONO (-8302 6025);
FORCEPROP 2 LAST CDS_LIB standard
J 0
(-8050 6025);
DISPLAY INVISIBLE (-8050 6025);
FORCEPROP 1 LAST OFFPAGE TRUE
J 0
(-7725 5900);
DISPLAY 0.872340 (-7725 5900);
PAINT GREEN (-7725 5900);
DISPLAY INVISIBLE (-7725 5900);
FORCEPROP 1 LAST COMMENT_BODY TRUE
J 0
(-7925 5925);
DISPLAY 0.872340 (-7925 5925);
PAINT GREEN (-7925 5925);
DISPLAY INVISIBLE (-7925 5925);
FORCEPROP 2 LAST PATH I359
J 0
(-8000 6100);
DISPLAY 0.680851 (-8000 6100);
DISPLAY INVISIBLE (-8000 6100);
FORCEADD TAP..6
R 2
(-3100 5750);
FORCEPROP 3 LASTPIN (-3150 5750) SIG_NAME P5E_CPU0_P0_TX_DN<0>
J 0
(-3140 5760);
DISPLAY 0.659574 (-3140 5760);
PAINT MONO (-3140 5760);
DISPLAY INVISIBLE (-3140 5760);
FORCEPROP 1 LASTPIN (-3150 5750) BN 0
J 2
(-3098 5758);
DISPLAY 0.680851 (-3098 5758);
PAINT MONO (-3098 5758);
FORCEPROP 2 LAST ROOM RISER1
J 0
(-3600 5800);
DISPLAY 0.829787 (-3600 5800);
PAINT RED (-3600 5800);
DISPLAY INVISIBLE (-3600 5800);
FORCEPROP 2 LAST BOM_COST IO_SLOT
J 0
(-3600 5850);
DISPLAY 0.829787 (-3600 5850);
DISPLAY INVISIBLE (-3600 5850);
FORCEPROP 2 LAST CDS_LIB mstr_standard
J 0
(-3100 5750);
DISPLAY INVISIBLE (-3100 5750);
FORCEPROP 1 LAST BODY_TYPE PLUMBING
J 2
(-3100 5700);
DISPLAY 0.702128 (-3100 5700);
PAINT GREEN (-3100 5700);
DISPLAY INVISIBLE (-3100 5700);
FORCEPROP 1 LAST HDL_TAP TRUE
J 2
(-3425 5625);
DISPLAY 0.702128 (-3425 5625);
PAINT GREEN (-3425 5625);
DISPLAY INVISIBLE (-3425 5625);
FORCEPROP 1 LAST PATH I360
J 2
(-3098 5750);
DISPLAY 0.872340 (-3098 5750);
PAINT GREEN (-3098 5750);
DISPLAY INVISIBLE (-3098 5750);
FORCEADD TAP..6
R 2
(-3100 5650);
FORCEPROP 3 LASTPIN (-3150 5650) SIG_NAME P5E_CPU0_P0_TX_DN<1>
J 0
(-3140 5660);
DISPLAY 0.659574 (-3140 5660);
PAINT MONO (-3140 5660);
DISPLAY INVISIBLE (-3140 5660);
FORCEPROP 1 LASTPIN (-3150 5650) BN 1
J 2
(-3098 5658);
DISPLAY 0.680851 (-3098 5658);
PAINT MONO (-3098 5658);
FORCEPROP 2 LAST ROOM RISER1
J 0
(-3600 5700);
DISPLAY 0.829787 (-3600 5700);
PAINT RED (-3600 5700);
DISPLAY INVISIBLE (-3600 5700);
FORCEPROP 2 LAST BOM_COST IO_SLOT
J 0
(-3600 5750);
DISPLAY 0.829787 (-3600 5750);
DISPLAY INVISIBLE (-3600 5750);
FORCEPROP 2 LAST CDS_LIB mstr_standard
J 0
(-3100 5650);
DISPLAY INVISIBLE (-3100 5650);
FORCEPROP 1 LAST BODY_TYPE PLUMBING
J 2
(-3100 5600);
DISPLAY 0.702128 (-3100 5600);
PAINT GREEN (-3100 5600);
DISPLAY INVISIBLE (-3100 5600);
FORCEPROP 1 LAST HDL_TAP TRUE
J 2
(-3425 5525);
DISPLAY 0.702128 (-3425 5525);
PAINT GREEN (-3425 5525);
DISPLAY INVISIBLE (-3425 5525);
FORCEPROP 1 LAST PATH I361
J 2
(-3098 5650);
DISPLAY 0.872340 (-3098 5650);
PAINT GREEN (-3098 5650);
DISPLAY INVISIBLE (-3098 5650);
FORCEADD TAP..6
R 2
(-3100 5550);
FORCEPROP 3 LASTPIN (-3150 5550) SIG_NAME P5E_CPU0_P0_TX_DN<2>
J 0
(-3140 5560);
DISPLAY 0.659574 (-3140 5560);
PAINT MONO (-3140 5560);
DISPLAY INVISIBLE (-3140 5560);
FORCEPROP 1 LASTPIN (-3150 5550) BN 2
J 2
(-3098 5558);
DISPLAY 0.680851 (-3098 5558);
PAINT MONO (-3098 5558);
FORCEPROP 2 LAST ROOM RISER1
J 0
(-3600 5600);
DISPLAY 0.829787 (-3600 5600);
PAINT RED (-3600 5600);
DISPLAY INVISIBLE (-3600 5600);
FORCEPROP 2 LAST BOM_COST IO_SLOT
J 0
(-3600 5650);
DISPLAY 0.829787 (-3600 5650);
DISPLAY INVISIBLE (-3600 5650);
FORCEPROP 2 LAST CDS_LIB standard
J 0
(-3100 5550);
DISPLAY INVISIBLE (-3100 5550);
FORCEPROP 1 LAST BODY_TYPE PLUMBING
J 2
(-3100 5500);
DISPLAY 0.702128 (-3100 5500);
PAINT GREEN (-3100 5500);
DISPLAY INVISIBLE (-3100 5500);
FORCEPROP 1 LAST HDL_TAP TRUE
J 2
(-3425 5425);
DISPLAY 0.702128 (-3425 5425);
PAINT GREEN (-3425 5425);
DISPLAY INVISIBLE (-3425 5425);
FORCEPROP 1 LAST PATH I362
J 2
(-3098 5550);
DISPLAY 0.872340 (-3098 5550);
PAINT GREEN (-3098 5550);
DISPLAY INVISIBLE (-3098 5550);
FORCEADD TAP..6
R 2
(-3250 5700);
FORCEPROP 3 LASTPIN (-3300 5700) SIG_NAME P5E_CPU0_P0_TX_DP<1>
J 0
(-3290 5710);
DISPLAY 0.659574 (-3290 5710);
PAINT MONO (-3290 5710);
DISPLAY INVISIBLE (-3290 5710);
FORCEPROP 1 LASTPIN (-3300 5700) BN 1
J 2
(-3248 5708);
DISPLAY 0.680851 (-3248 5708);
PAINT MONO (-3248 5708);
FORCEPROP 2 LAST ROOM RISER1
J 0
(-3750 5750);
DISPLAY 0.829787 (-3750 5750);
PAINT RED (-3750 5750);
DISPLAY INVISIBLE (-3750 5750);
FORCEPROP 2 LAST BOM_COST IO_SLOT
J 0
(-3750 5800);
DISPLAY 0.829787 (-3750 5800);
DISPLAY INVISIBLE (-3750 5800);
FORCEPROP 2 LAST CDS_LIB mstr_standard
J 0
(-3250 5700);
DISPLAY INVISIBLE (-3250 5700);
FORCEPROP 1 LAST BODY_TYPE PLUMBING
J 2
(-3250 5650);
DISPLAY 0.702128 (-3250 5650);
PAINT GREEN (-3250 5650);
DISPLAY INVISIBLE (-3250 5650);
FORCEPROP 1 LAST HDL_TAP TRUE
J 2
(-3575 5575);
DISPLAY 0.702128 (-3575 5575);
PAINT GREEN (-3575 5575);
DISPLAY INVISIBLE (-3575 5575);
FORCEPROP 1 LAST PATH I363
J 2
(-3248 5700);
DISPLAY 0.872340 (-3248 5700);
PAINT GREEN (-3248 5700);
DISPLAY INVISIBLE (-3248 5700);
FORCEADD TAP..6
R 2
(-3250 5800);
FORCEPROP 3 LASTPIN (-3300 5800) SIG_NAME P5E_CPU0_P0_TX_DP<0>
J 0
(-3290 5810);
DISPLAY 0.659574 (-3290 5810);
PAINT MONO (-3290 5810);
DISPLAY INVISIBLE (-3290 5810);
FORCEPROP 1 LASTPIN (-3300 5800) BN 0
J 2
(-3248 5808);
DISPLAY 0.680851 (-3248 5808);
PAINT MONO (-3248 5808);
FORCEPROP 2 LAST ROOM RISER1
J 0
(-3750 5850);
DISPLAY 0.829787 (-3750 5850);
PAINT RED (-3750 5850);
DISPLAY INVISIBLE (-3750 5850);
FORCEPROP 2 LAST BOM_COST IO_SLOT
J 0
(-3750 5900);
DISPLAY 0.829787 (-3750 5900);
DISPLAY INVISIBLE (-3750 5900);
FORCEPROP 2 LAST CDS_LIB mstr_standard
J 0
(-3250 5800);
DISPLAY INVISIBLE (-3250 5800);
FORCEPROP 1 LAST BODY_TYPE PLUMBING
J 2
(-3250 5750);
DISPLAY 0.702128 (-3250 5750);
PAINT GREEN (-3250 5750);
DISPLAY INVISIBLE (-3250 5750);
FORCEPROP 1 LAST HDL_TAP TRUE
J 2
(-3575 5675);
DISPLAY 0.702128 (-3575 5675);
PAINT GREEN (-3575 5675);
DISPLAY INVISIBLE (-3575 5675);
FORCEPROP 1 LAST PATH I364
J 2
(-3248 5800);
DISPLAY 0.872340 (-3248 5800);
PAINT GREEN (-3248 5800);
DISPLAY INVISIBLE (-3248 5800);
FORCEADD TAP..6
R 2
(-3250 5600);
FORCEPROP 3 LASTPIN (-3300 5600) SIG_NAME P5E_CPU0_P0_TX_DP<2>
J 0
(-3290 5610);
DISPLAY 0.659574 (-3290 5610);
PAINT MONO (-3290 5610);
DISPLAY INVISIBLE (-3290 5610);
FORCEPROP 1 LASTPIN (-3300 5600) BN 2
J 2
(-3248 5608);
DISPLAY 0.680851 (-3248 5608);
PAINT MONO (-3248 5608);
FORCEPROP 2 LAST ROOM RISER1
J 0
(-3750 5650);
DISPLAY 0.829787 (-3750 5650);
PAINT RED (-3750 5650);
DISPLAY INVISIBLE (-3750 5650);
FORCEPROP 2 LAST BOM_COST IO_SLOT
J 0
(-3750 5700);
DISPLAY 0.829787 (-3750 5700);
DISPLAY INVISIBLE (-3750 5700);
FORCEPROP 2 LAST CDS_LIB standard
J 0
(-3250 5600);
DISPLAY INVISIBLE (-3250 5600);
FORCEPROP 1 LAST BODY_TYPE PLUMBING
J 2
(-3250 5550);
DISPLAY 0.702128 (-3250 5550);
PAINT GREEN (-3250 5550);
DISPLAY INVISIBLE (-3250 5550);
FORCEPROP 1 LAST HDL_TAP TRUE
J 2
(-3575 5475);
DISPLAY 0.702128 (-3575 5475);
PAINT GREEN (-3575 5475);
DISPLAY INVISIBLE (-3575 5475);
FORCEPROP 1 LAST PATH I365
J 2
(-3248 5600);
DISPLAY 0.872340 (-3248 5600);
PAINT GREEN (-3248 5600);
DISPLAY INVISIBLE (-3248 5600);
FORCEADD TAP..6
R 2
(-3100 5450);
FORCEPROP 3 LASTPIN (-3150 5450) SIG_NAME P5E_CPU0_P0_TX_DN<3>
J 0
(-3140 5460);
DISPLAY 0.659574 (-3140 5460);
PAINT MONO (-3140 5460);
DISPLAY INVISIBLE (-3140 5460);
FORCEPROP 1 LASTPIN (-3150 5450) BN 3
J 2
(-3098 5458);
DISPLAY 0.680851 (-3098 5458);
PAINT MONO (-3098 5458);
FORCEPROP 2 LAST ROOM RISER1
J 0
(-3600 5500);
DISPLAY 0.829787 (-3600 5500);
PAINT RED (-3600 5500);
DISPLAY INVISIBLE (-3600 5500);
FORCEPROP 2 LAST BOM_COST IO_SLOT
J 0
(-3600 5550);
DISPLAY 0.829787 (-3600 5550);
DISPLAY INVISIBLE (-3600 5550);
FORCEPROP 2 LAST CDS_LIB standard
J 0
(-3100 5450);
DISPLAY INVISIBLE (-3100 5450);
FORCEPROP 1 LAST BODY_TYPE PLUMBING
J 2
(-3100 5400);
DISPLAY 0.702128 (-3100 5400);
PAINT GREEN (-3100 5400);
DISPLAY INVISIBLE (-3100 5400);
FORCEPROP 1 LAST HDL_TAP TRUE
J 2
(-3425 5325);
DISPLAY 0.702128 (-3425 5325);
PAINT GREEN (-3425 5325);
DISPLAY INVISIBLE (-3425 5325);
FORCEPROP 1 LAST PATH I366
J 2
(-3098 5450);
DISPLAY 0.872340 (-3098 5450);
PAINT GREEN (-3098 5450);
DISPLAY INVISIBLE (-3098 5450);
FORCEADD TAP..6
R 2
(-3100 5350);
FORCEPROP 3 LASTPIN (-3150 5350) SIG_NAME P5E_CPU0_P0_TX_DN<4>
J 0
(-3140 5360);
DISPLAY 0.659574 (-3140 5360);
PAINT MONO (-3140 5360);
DISPLAY INVISIBLE (-3140 5360);
FORCEPROP 1 LASTPIN (-3150 5350) BN 4
J 2
(-3098 5358);
DISPLAY 0.680851 (-3098 5358);
PAINT MONO (-3098 5358);
FORCEPROP 2 LAST ROOM RISER1
J 0
(-3600 5400);
DISPLAY 0.829787 (-3600 5400);
PAINT RED (-3600 5400);
DISPLAY INVISIBLE (-3600 5400);
FORCEPROP 2 LAST BOM_COST IO_SLOT
J 0
(-3600 5450);
DISPLAY 0.829787 (-3600 5450);
DISPLAY INVISIBLE (-3600 5450);
FORCEPROP 2 LAST CDS_LIB standard
J 0
(-3100 5350);
DISPLAY INVISIBLE (-3100 5350);
FORCEPROP 1 LAST BODY_TYPE PLUMBING
J 2
(-3100 5300);
DISPLAY 0.702128 (-3100 5300);
PAINT GREEN (-3100 5300);
DISPLAY INVISIBLE (-3100 5300);
FORCEPROP 1 LAST HDL_TAP TRUE
J 2
(-3425 5225);
DISPLAY 0.702128 (-3425 5225);
PAINT GREEN (-3425 5225);
DISPLAY INVISIBLE (-3425 5225);
FORCEPROP 1 LAST PATH I367
J 2
(-3098 5350);
DISPLAY 0.872340 (-3098 5350);
PAINT GREEN (-3098 5350);
DISPLAY INVISIBLE (-3098 5350);
FORCEADD TAP..6
R 2
(-3100 5150);
FORCEPROP 3 LASTPIN (-3150 5150) SIG_NAME P5E_CPU0_P0_TX_DN<6>
J 0
(-3140 5160);
DISPLAY 0.659574 (-3140 5160);
PAINT MONO (-3140 5160);
DISPLAY INVISIBLE (-3140 5160);
FORCEPROP 1 LASTPIN (-3150 5150) BN 6
J 2
(-3098 5158);
DISPLAY 0.680851 (-3098 5158);
PAINT MONO (-3098 5158);
FORCEPROP 2 LAST ROOM RISER1
J 0
(-3600 5200);
DISPLAY 0.829787 (-3600 5200);
PAINT RED (-3600 5200);
DISPLAY INVISIBLE (-3600 5200);
FORCEPROP 2 LAST BOM_COST IO_SLOT
J 0
(-3600 5250);
DISPLAY 0.829787 (-3600 5250);
DISPLAY INVISIBLE (-3600 5250);
FORCEPROP 2 LAST CDS_LIB standard
J 0
(-3100 5150);
DISPLAY INVISIBLE (-3100 5150);
FORCEPROP 1 LAST BODY_TYPE PLUMBING
J 2
(-3100 5100);
DISPLAY 0.702128 (-3100 5100);
PAINT GREEN (-3100 5100);
DISPLAY INVISIBLE (-3100 5100);
FORCEPROP 1 LAST HDL_TAP TRUE
J 2
(-3425 5025);
DISPLAY 0.702128 (-3425 5025);
PAINT GREEN (-3425 5025);
DISPLAY INVISIBLE (-3425 5025);
FORCEPROP 1 LAST PATH I368
J 2
(-3098 5150);
DISPLAY 0.872340 (-3098 5150);
PAINT GREEN (-3098 5150);
DISPLAY INVISIBLE (-3098 5150);
FORCEADD TAP..6
R 2
(-3100 5250);
FORCEPROP 3 LASTPIN (-3150 5250) SIG_NAME P5E_CPU0_P0_TX_DN<5>
J 0
(-3140 5260);
DISPLAY 0.659574 (-3140 5260);
PAINT MONO (-3140 5260);
DISPLAY INVISIBLE (-3140 5260);
FORCEPROP 1 LASTPIN (-3150 5250) BN 5
J 2
(-3098 5258);
DISPLAY 0.680851 (-3098 5258);
PAINT MONO (-3098 5258);
FORCEPROP 2 LAST ROOM RISER1
J 0
(-3600 5300);
DISPLAY 0.829787 (-3600 5300);
PAINT RED (-3600 5300);
DISPLAY INVISIBLE (-3600 5300);
FORCEPROP 2 LAST BOM_COST IO_SLOT
J 0
(-3600 5350);
DISPLAY 0.829787 (-3600 5350);
DISPLAY INVISIBLE (-3600 5350);
FORCEPROP 2 LAST CDS_LIB standard
J 0
(-3100 5250);
DISPLAY INVISIBLE (-3100 5250);
FORCEPROP 1 LAST BODY_TYPE PLUMBING
J 2
(-3100 5200);
DISPLAY 0.702128 (-3100 5200);
PAINT GREEN (-3100 5200);
DISPLAY INVISIBLE (-3100 5200);
FORCEPROP 1 LAST HDL_TAP TRUE
J 2
(-3425 5125);
DISPLAY 0.702128 (-3425 5125);
PAINT GREEN (-3425 5125);
DISPLAY INVISIBLE (-3425 5125);
FORCEPROP 1 LAST PATH I369
J 2
(-3098 5250);
DISPLAY 0.872340 (-3098 5250);
PAINT GREEN (-3098 5250);
DISPLAY INVISIBLE (-3098 5250);
FORCEADD TAP..6
R 2
(-3100 5050);
FORCEPROP 3 LASTPIN (-3150 5050) SIG_NAME P5E_CPU0_P0_TX_DN<7>
J 0
(-3140 5060);
DISPLAY 0.659574 (-3140 5060);
PAINT MONO (-3140 5060);
DISPLAY INVISIBLE (-3140 5060);
FORCEPROP 1 LASTPIN (-3150 5050) BN 7
J 2
(-3098 5058);
DISPLAY 0.680851 (-3098 5058);
PAINT MONO (-3098 5058);
FORCEPROP 2 LAST ROOM RISER1
J 0
(-3600 5100);
DISPLAY 0.829787 (-3600 5100);
PAINT RED (-3600 5100);
DISPLAY INVISIBLE (-3600 5100);
FORCEPROP 2 LAST BOM_COST IO_SLOT
J 0
(-3600 5150);
DISPLAY 0.829787 (-3600 5150);
DISPLAY INVISIBLE (-3600 5150);
FORCEPROP 2 LAST CDS_LIB standard
J 0
(-3100 5050);
DISPLAY INVISIBLE (-3100 5050);
FORCEPROP 1 LAST BODY_TYPE PLUMBING
J 2
(-3100 5000);
DISPLAY 0.702128 (-3100 5000);
PAINT GREEN (-3100 5000);
DISPLAY INVISIBLE (-3100 5000);
FORCEPROP 1 LAST HDL_TAP TRUE
J 2
(-3425 4925);
DISPLAY 0.702128 (-3425 4925);
PAINT GREEN (-3425 4925);
DISPLAY INVISIBLE (-3425 4925);
FORCEPROP 1 LAST PATH I370
J 2
(-3098 5050);
DISPLAY 0.872340 (-3098 5050);
PAINT GREEN (-3098 5050);
DISPLAY INVISIBLE (-3098 5050);
FORCEADD TAP..6
R 2
(-3250 5300);
FORCEPROP 3 LASTPIN (-3300 5300) SIG_NAME P5E_CPU0_P0_TX_DP<5>
J 0
(-3290 5310);
DISPLAY 0.659574 (-3290 5310);
PAINT MONO (-3290 5310);
DISPLAY INVISIBLE (-3290 5310);
FORCEPROP 1 LASTPIN (-3300 5300) BN 5
J 2
(-3248 5308);
DISPLAY 0.680851 (-3248 5308);
PAINT MONO (-3248 5308);
FORCEPROP 2 LAST ROOM RISER1
J 0
(-3750 5350);
DISPLAY 0.829787 (-3750 5350);
PAINT RED (-3750 5350);
DISPLAY INVISIBLE (-3750 5350);
FORCEPROP 2 LAST BOM_COST IO_SLOT
J 0
(-3750 5400);
DISPLAY 0.829787 (-3750 5400);
DISPLAY INVISIBLE (-3750 5400);
FORCEPROP 2 LAST CDS_LIB standard
J 0
(-3250 5300);
DISPLAY INVISIBLE (-3250 5300);
FORCEPROP 1 LAST BODY_TYPE PLUMBING
J 2
(-3250 5250);
DISPLAY 0.702128 (-3250 5250);
PAINT GREEN (-3250 5250);
DISPLAY INVISIBLE (-3250 5250);
FORCEPROP 1 LAST HDL_TAP TRUE
J 2
(-3575 5175);
DISPLAY 0.702128 (-3575 5175);
PAINT GREEN (-3575 5175);
DISPLAY INVISIBLE (-3575 5175);
FORCEPROP 1 LAST PATH I371
J 2
(-3248 5300);
DISPLAY 0.872340 (-3248 5300);
PAINT GREEN (-3248 5300);
DISPLAY INVISIBLE (-3248 5300);
FORCEADD TAP..6
R 2
(-3250 5400);
FORCEPROP 3 LASTPIN (-3300 5400) SIG_NAME P5E_CPU0_P0_TX_DP<4>
J 0
(-3290 5410);
DISPLAY 0.659574 (-3290 5410);
PAINT MONO (-3290 5410);
DISPLAY INVISIBLE (-3290 5410);
FORCEPROP 1 LASTPIN (-3300 5400) BN 4
J 2
(-3248 5408);
DISPLAY 0.680851 (-3248 5408);
PAINT MONO (-3248 5408);
FORCEPROP 2 LAST ROOM RISER1
J 0
(-3750 5450);
DISPLAY 0.829787 (-3750 5450);
PAINT RED (-3750 5450);
DISPLAY INVISIBLE (-3750 5450);
FORCEPROP 2 LAST BOM_COST IO_SLOT
J 0
(-3750 5500);
DISPLAY 0.829787 (-3750 5500);
DISPLAY INVISIBLE (-3750 5500);
FORCEPROP 2 LAST CDS_LIB standard
J 0
(-3250 5400);
DISPLAY INVISIBLE (-3250 5400);
FORCEPROP 1 LAST BODY_TYPE PLUMBING
J 2
(-3250 5350);
DISPLAY 0.702128 (-3250 5350);
PAINT GREEN (-3250 5350);
DISPLAY INVISIBLE (-3250 5350);
FORCEPROP 1 LAST HDL_TAP TRUE
J 2
(-3575 5275);
DISPLAY 0.702128 (-3575 5275);
PAINT GREEN (-3575 5275);
DISPLAY INVISIBLE (-3575 5275);
FORCEPROP 1 LAST PATH I372
J 2
(-3248 5400);
DISPLAY 0.872340 (-3248 5400);
PAINT GREEN (-3248 5400);
DISPLAY INVISIBLE (-3248 5400);
FORCEADD TAP..6
R 2
(-3250 5500);
FORCEPROP 3 LASTPIN (-3300 5500) SIG_NAME P5E_CPU0_P0_TX_DP<3>
J 0
(-3290 5510);
DISPLAY 0.659574 (-3290 5510);
PAINT MONO (-3290 5510);
DISPLAY INVISIBLE (-3290 5510);
FORCEPROP 1 LASTPIN (-3300 5500) BN 3
J 2
(-3248 5508);
DISPLAY 0.680851 (-3248 5508);
PAINT MONO (-3248 5508);
FORCEPROP 2 LAST ROOM RISER1
J 0
(-3750 5550);
DISPLAY 0.829787 (-3750 5550);
PAINT RED (-3750 5550);
DISPLAY INVISIBLE (-3750 5550);
FORCEPROP 2 LAST BOM_COST IO_SLOT
J 0
(-3750 5600);
DISPLAY 0.829787 (-3750 5600);
DISPLAY INVISIBLE (-3750 5600);
FORCEPROP 2 LAST CDS_LIB standard
J 0
(-3250 5500);
DISPLAY INVISIBLE (-3250 5500);
FORCEPROP 1 LAST BODY_TYPE PLUMBING
J 2
(-3250 5450);
DISPLAY 0.702128 (-3250 5450);
PAINT GREEN (-3250 5450);
DISPLAY INVISIBLE (-3250 5450);
FORCEPROP 1 LAST HDL_TAP TRUE
J 2
(-3575 5375);
DISPLAY 0.702128 (-3575 5375);
PAINT GREEN (-3575 5375);
DISPLAY INVISIBLE (-3575 5375);
FORCEPROP 1 LAST PATH I373
J 2
(-3248 5500);
DISPLAY 0.872340 (-3248 5500);
PAINT GREEN (-3248 5500);
DISPLAY INVISIBLE (-3248 5500);
FORCEADD TAP..6
R 2
(-3250 5100);
FORCEPROP 3 LASTPIN (-3300 5100) SIG_NAME P5E_CPU0_P0_TX_DP<7>
J 0
(-3290 5110);
DISPLAY 0.659574 (-3290 5110);
PAINT MONO (-3290 5110);
DISPLAY INVISIBLE (-3290 5110);
FORCEPROP 1 LASTPIN (-3300 5100) BN 7
J 2
(-3248 5108);
DISPLAY 0.680851 (-3248 5108);
PAINT MONO (-3248 5108);
FORCEPROP 2 LAST ROOM RISER1
J 0
(-3750 5150);
DISPLAY 0.829787 (-3750 5150);
PAINT RED (-3750 5150);
DISPLAY INVISIBLE (-3750 5150);
FORCEPROP 2 LAST BOM_COST IO_SLOT
J 0
(-3750 5200);
DISPLAY 0.829787 (-3750 5200);
DISPLAY INVISIBLE (-3750 5200);
FORCEPROP 2 LAST CDS_LIB standard
J 0
(-3250 5100);
DISPLAY INVISIBLE (-3250 5100);
FORCEPROP 1 LAST BODY_TYPE PLUMBING
J 2
(-3250 5050);
DISPLAY 0.702128 (-3250 5050);
PAINT GREEN (-3250 5050);
DISPLAY INVISIBLE (-3250 5050);
FORCEPROP 1 LAST HDL_TAP TRUE
J 2
(-3575 4975);
DISPLAY 0.702128 (-3575 4975);
PAINT GREEN (-3575 4975);
DISPLAY INVISIBLE (-3575 4975);
FORCEPROP 1 LAST PATH I374
J 2
(-3248 5100);
DISPLAY 0.872340 (-3248 5100);
PAINT GREEN (-3248 5100);
DISPLAY INVISIBLE (-3248 5100);
FORCEADD TAP..6
R 2
(-3250 5200);
FORCEPROP 3 LASTPIN (-3300 5200) SIG_NAME P5E_CPU0_P0_TX_DP<6>
J 0
(-3290 5210);
DISPLAY 0.659574 (-3290 5210);
PAINT MONO (-3290 5210);
DISPLAY INVISIBLE (-3290 5210);
FORCEPROP 1 LASTPIN (-3300 5200) BN 6
J 2
(-3248 5208);
DISPLAY 0.680851 (-3248 5208);
PAINT MONO (-3248 5208);
FORCEPROP 2 LAST ROOM RISER1
J 0
(-3750 5250);
DISPLAY 0.829787 (-3750 5250);
PAINT RED (-3750 5250);
DISPLAY INVISIBLE (-3750 5250);
FORCEPROP 2 LAST BOM_COST IO_SLOT
J 0
(-3750 5300);
DISPLAY 0.829787 (-3750 5300);
DISPLAY INVISIBLE (-3750 5300);
FORCEPROP 2 LAST CDS_LIB standard
J 0
(-3250 5200);
DISPLAY INVISIBLE (-3250 5200);
FORCEPROP 1 LAST BODY_TYPE PLUMBING
J 2
(-3250 5150);
DISPLAY 0.702128 (-3250 5150);
PAINT GREEN (-3250 5150);
DISPLAY INVISIBLE (-3250 5150);
FORCEPROP 1 LAST HDL_TAP TRUE
J 2
(-3575 5075);
DISPLAY 0.702128 (-3575 5075);
PAINT GREEN (-3575 5075);
DISPLAY INVISIBLE (-3575 5075);
FORCEPROP 1 LAST PATH I375
J 2
(-3248 5200);
DISPLAY 0.872340 (-3248 5200);
PAINT GREEN (-3248 5200);
DISPLAY INVISIBLE (-3248 5200);
FORCEADD TAP..6
R 2
(-3100 4950);
FORCEPROP 3 LASTPIN (-3150 4950) SIG_NAME P5E_CPU0_P0_TX_DN<8>
J 0
(-3140 4960);
DISPLAY 0.659574 (-3140 4960);
PAINT MONO (-3140 4960);
DISPLAY INVISIBLE (-3140 4960);
FORCEPROP 1 LASTPIN (-3150 4950) BN 8
J 2
(-3098 4958);
DISPLAY 0.680851 (-3098 4958);
PAINT MONO (-3098 4958);
FORCEPROP 2 LAST ROOM RISER1
J 0
(-3600 5000);
DISPLAY 0.829787 (-3600 5000);
PAINT RED (-3600 5000);
DISPLAY INVISIBLE (-3600 5000);
FORCEPROP 2 LAST BOM_COST IO_SLOT
J 0
(-3600 5050);
DISPLAY 0.829787 (-3600 5050);
DISPLAY INVISIBLE (-3600 5050);
FORCEPROP 2 LAST CDS_LIB standard
J 0
(-3100 4950);
DISPLAY INVISIBLE (-3100 4950);
FORCEPROP 1 LAST BODY_TYPE PLUMBING
J 2
(-3100 4900);
DISPLAY 0.702128 (-3100 4900);
PAINT GREEN (-3100 4900);
DISPLAY INVISIBLE (-3100 4900);
FORCEPROP 1 LAST HDL_TAP TRUE
J 2
(-3425 4825);
DISPLAY 0.702128 (-3425 4825);
PAINT GREEN (-3425 4825);
DISPLAY INVISIBLE (-3425 4825);
FORCEPROP 1 LAST PATH I376
J 2
(-3098 4950);
DISPLAY 0.872340 (-3098 4950);
PAINT GREEN (-3098 4950);
DISPLAY INVISIBLE (-3098 4950);
FORCEADD TAP..6
R 2
(-3100 4850);
FORCEPROP 3 LASTPIN (-3150 4850) SIG_NAME P5E_CPU0_P0_TX_DN<9>
J 0
(-3140 4860);
DISPLAY 0.659574 (-3140 4860);
PAINT MONO (-3140 4860);
DISPLAY INVISIBLE (-3140 4860);
FORCEPROP 1 LASTPIN (-3150 4850) BN 9
J 2
(-3098 4858);
DISPLAY 0.680851 (-3098 4858);
PAINT MONO (-3098 4858);
FORCEPROP 2 LAST ROOM RISER1
J 0
(-3600 4900);
DISPLAY 0.829787 (-3600 4900);
PAINT RED (-3600 4900);
DISPLAY INVISIBLE (-3600 4900);
FORCEPROP 2 LAST BOM_COST IO_SLOT
J 0
(-3600 4950);
DISPLAY 0.829787 (-3600 4950);
DISPLAY INVISIBLE (-3600 4950);
FORCEPROP 2 LAST CDS_LIB standard
J 0
(-3100 4850);
DISPLAY INVISIBLE (-3100 4850);
FORCEPROP 1 LAST BODY_TYPE PLUMBING
J 2
(-3100 4800);
DISPLAY 0.702128 (-3100 4800);
PAINT GREEN (-3100 4800);
DISPLAY INVISIBLE (-3100 4800);
FORCEPROP 1 LAST HDL_TAP TRUE
J 2
(-3425 4725);
DISPLAY 0.702128 (-3425 4725);
PAINT GREEN (-3425 4725);
DISPLAY INVISIBLE (-3425 4725);
FORCEPROP 1 LAST PATH I377
J 2
(-3098 4850);
DISPLAY 0.872340 (-3098 4850);
PAINT GREEN (-3098 4850);
DISPLAY INVISIBLE (-3098 4850);
FORCEADD TAP..6
R 2
(-3100 4650);
FORCEPROP 3 LASTPIN (-3150 4650) SIG_NAME P5E_CPU0_P0_TX_DN<11>
J 0
(-3140 4660);
DISPLAY 0.659574 (-3140 4660);
PAINT MONO (-3140 4660);
DISPLAY INVISIBLE (-3140 4660);
FORCEPROP 1 LASTPIN (-3150 4650) BN 11
J 2
(-3098 4658);
DISPLAY 0.680851 (-3098 4658);
PAINT MONO (-3098 4658);
FORCEPROP 2 LAST ROOM RISER1
J 0
(-3600 4700);
DISPLAY 0.829787 (-3600 4700);
PAINT RED (-3600 4700);
DISPLAY INVISIBLE (-3600 4700);
FORCEPROP 2 LAST BOM_COST IO_SLOT
J 0
(-3600 4750);
DISPLAY 0.829787 (-3600 4750);
DISPLAY INVISIBLE (-3600 4750);
FORCEPROP 2 LAST CDS_LIB standard
J 0
(-3100 4650);
DISPLAY INVISIBLE (-3100 4650);
FORCEPROP 1 LAST BODY_TYPE PLUMBING
J 2
(-3100 4600);
DISPLAY 0.702128 (-3100 4600);
PAINT GREEN (-3100 4600);
DISPLAY INVISIBLE (-3100 4600);
FORCEPROP 1 LAST HDL_TAP TRUE
J 2
(-3425 4525);
DISPLAY 0.702128 (-3425 4525);
PAINT GREEN (-3425 4525);
DISPLAY INVISIBLE (-3425 4525);
FORCEPROP 1 LAST PATH I378
J 2
(-3098 4650);
DISPLAY 0.872340 (-3098 4650);
PAINT GREEN (-3098 4650);
DISPLAY INVISIBLE (-3098 4650);
FORCEADD TAP..6
R 2
(-3100 4750);
FORCEPROP 3 LASTPIN (-3150 4750) SIG_NAME P5E_CPU0_P0_TX_DN<10>
J 0
(-3140 4760);
DISPLAY 0.659574 (-3140 4760);
PAINT MONO (-3140 4760);
DISPLAY INVISIBLE (-3140 4760);
FORCEPROP 1 LASTPIN (-3150 4750) BN 10
J 2
(-3098 4758);
DISPLAY 0.680851 (-3098 4758);
PAINT MONO (-3098 4758);
FORCEPROP 2 LAST ROOM RISER1
J 0
(-3600 4800);
DISPLAY 0.829787 (-3600 4800);
PAINT RED (-3600 4800);
DISPLAY INVISIBLE (-3600 4800);
FORCEPROP 2 LAST BOM_COST IO_SLOT
J 0
(-3600 4850);
DISPLAY 0.829787 (-3600 4850);
DISPLAY INVISIBLE (-3600 4850);
FORCEPROP 2 LAST CDS_LIB standard
J 0
(-3100 4750);
DISPLAY INVISIBLE (-3100 4750);
FORCEPROP 1 LAST BODY_TYPE PLUMBING
J 2
(-3100 4700);
DISPLAY 0.702128 (-3100 4700);
PAINT GREEN (-3100 4700);
DISPLAY INVISIBLE (-3100 4700);
FORCEPROP 1 LAST HDL_TAP TRUE
J 2
(-3425 4625);
DISPLAY 0.702128 (-3425 4625);
PAINT GREEN (-3425 4625);
DISPLAY INVISIBLE (-3425 4625);
FORCEPROP 1 LAST PATH I379
J 2
(-3098 4750);
DISPLAY 0.872340 (-3098 4750);
PAINT GREEN (-3098 4750);
DISPLAY INVISIBLE (-3098 4750);
FORCEADD TAP..6
R 2
(-3100 4550);
FORCEPROP 3 LASTPIN (-3150 4550) SIG_NAME P5E_CPU0_P0_TX_DN<12>
J 0
(-3140 4560);
DISPLAY 0.659574 (-3140 4560);
PAINT MONO (-3140 4560);
DISPLAY INVISIBLE (-3140 4560);
FORCEPROP 1 LASTPIN (-3150 4550) BN 12
J 2
(-3098 4558);
DISPLAY 0.680851 (-3098 4558);
PAINT MONO (-3098 4558);
FORCEPROP 2 LAST ROOM RISER1
J 0
(-3600 4600);
DISPLAY 0.829787 (-3600 4600);
PAINT RED (-3600 4600);
DISPLAY INVISIBLE (-3600 4600);
FORCEPROP 2 LAST BOM_COST IO_SLOT
J 0
(-3600 4650);
DISPLAY 0.829787 (-3600 4650);
DISPLAY INVISIBLE (-3600 4650);
FORCEPROP 2 LAST CDS_LIB standard
J 0
(-3100 4550);
DISPLAY INVISIBLE (-3100 4550);
FORCEPROP 1 LAST BODY_TYPE PLUMBING
J 2
(-3100 4500);
DISPLAY 0.702128 (-3100 4500);
PAINT GREEN (-3100 4500);
DISPLAY INVISIBLE (-3100 4500);
FORCEPROP 1 LAST HDL_TAP TRUE
J 2
(-3425 4425);
DISPLAY 0.702128 (-3425 4425);
PAINT GREEN (-3425 4425);
DISPLAY INVISIBLE (-3425 4425);
FORCEPROP 1 LAST PATH I380
J 2
(-3098 4550);
DISPLAY 0.872340 (-3098 4550);
PAINT GREEN (-3098 4550);
DISPLAY INVISIBLE (-3098 4550);
FORCEADD TAP..6
R 2
(-3250 4800);
FORCEPROP 3 LASTPIN (-3300 4800) SIG_NAME P5E_CPU0_P0_TX_DP<10>
J 0
(-3290 4810);
DISPLAY 0.659574 (-3290 4810);
PAINT MONO (-3290 4810);
DISPLAY INVISIBLE (-3290 4810);
FORCEPROP 1 LASTPIN (-3300 4800) BN 10
J 2
(-3248 4808);
DISPLAY 0.680851 (-3248 4808);
PAINT MONO (-3248 4808);
FORCEPROP 2 LAST ROOM RISER1
J 0
(-3750 4850);
DISPLAY 0.829787 (-3750 4850);
PAINT RED (-3750 4850);
DISPLAY INVISIBLE (-3750 4850);
FORCEPROP 2 LAST BOM_COST IO_SLOT
J 0
(-3750 4900);
DISPLAY 0.829787 (-3750 4900);
DISPLAY INVISIBLE (-3750 4900);
FORCEPROP 2 LAST CDS_LIB standard
J 0
(-3250 4800);
DISPLAY INVISIBLE (-3250 4800);
FORCEPROP 1 LAST BODY_TYPE PLUMBING
J 2
(-3250 4750);
DISPLAY 0.702128 (-3250 4750);
PAINT GREEN (-3250 4750);
DISPLAY INVISIBLE (-3250 4750);
FORCEPROP 1 LAST HDL_TAP TRUE
J 2
(-3575 4675);
DISPLAY 0.702128 (-3575 4675);
PAINT GREEN (-3575 4675);
DISPLAY INVISIBLE (-3575 4675);
FORCEPROP 1 LAST PATH I381
J 2
(-3248 4800);
DISPLAY 0.872340 (-3248 4800);
PAINT GREEN (-3248 4800);
DISPLAY INVISIBLE (-3248 4800);
FORCEADD TAP..6
R 2
(-3250 4900);
FORCEPROP 3 LASTPIN (-3300 4900) SIG_NAME P5E_CPU0_P0_TX_DP<9>
J 0
(-3290 4910);
DISPLAY 0.659574 (-3290 4910);
PAINT MONO (-3290 4910);
DISPLAY INVISIBLE (-3290 4910);
FORCEPROP 1 LASTPIN (-3300 4900) BN 9
J 2
(-3248 4908);
DISPLAY 0.680851 (-3248 4908);
PAINT MONO (-3248 4908);
FORCEPROP 2 LAST ROOM RISER1
J 0
(-3750 4950);
DISPLAY 0.829787 (-3750 4950);
PAINT RED (-3750 4950);
DISPLAY INVISIBLE (-3750 4950);
FORCEPROP 2 LAST BOM_COST IO_SLOT
J 0
(-3750 5000);
DISPLAY 0.829787 (-3750 5000);
DISPLAY INVISIBLE (-3750 5000);
FORCEPROP 2 LAST CDS_LIB standard
J 0
(-3250 4900);
DISPLAY INVISIBLE (-3250 4900);
FORCEPROP 1 LAST BODY_TYPE PLUMBING
J 2
(-3250 4850);
DISPLAY 0.702128 (-3250 4850);
PAINT GREEN (-3250 4850);
DISPLAY INVISIBLE (-3250 4850);
FORCEPROP 1 LAST HDL_TAP TRUE
J 2
(-3575 4775);
DISPLAY 0.702128 (-3575 4775);
PAINT GREEN (-3575 4775);
DISPLAY INVISIBLE (-3575 4775);
FORCEPROP 1 LAST PATH I382
J 2
(-3248 4900);
DISPLAY 0.872340 (-3248 4900);
PAINT GREEN (-3248 4900);
DISPLAY INVISIBLE (-3248 4900);
FORCEADD TAP..6
R 2
(-3250 5000);
FORCEPROP 3 LASTPIN (-3300 5000) SIG_NAME P5E_CPU0_P0_TX_DP<8>
J 0
(-3290 5010);
DISPLAY 0.659574 (-3290 5010);
PAINT MONO (-3290 5010);
DISPLAY INVISIBLE (-3290 5010);
FORCEPROP 1 LASTPIN (-3300 5000) BN 8
J 2
(-3248 5008);
DISPLAY 0.680851 (-3248 5008);
PAINT MONO (-3248 5008);
FORCEPROP 2 LAST ROOM RISER1
J 0
(-3750 5050);
DISPLAY 0.829787 (-3750 5050);
PAINT RED (-3750 5050);
DISPLAY INVISIBLE (-3750 5050);
FORCEPROP 2 LAST BOM_COST IO_SLOT
J 0
(-3750 5100);
DISPLAY 0.829787 (-3750 5100);
DISPLAY INVISIBLE (-3750 5100);
FORCEPROP 2 LAST CDS_LIB standard
J 0
(-3250 5000);
DISPLAY INVISIBLE (-3250 5000);
FORCEPROP 1 LAST BODY_TYPE PLUMBING
J 2
(-3250 4950);
DISPLAY 0.702128 (-3250 4950);
PAINT GREEN (-3250 4950);
DISPLAY INVISIBLE (-3250 4950);
FORCEPROP 1 LAST HDL_TAP TRUE
J 2
(-3575 4875);
DISPLAY 0.702128 (-3575 4875);
PAINT GREEN (-3575 4875);
DISPLAY INVISIBLE (-3575 4875);
FORCEPROP 1 LAST PATH I383
J 2
(-3248 5000);
DISPLAY 0.872340 (-3248 5000);
PAINT GREEN (-3248 5000);
DISPLAY INVISIBLE (-3248 5000);
FORCEADD TAP..6
R 2
(-3250 4500);
FORCEPROP 3 LASTPIN (-3300 4500) SIG_NAME P5E_CPU0_P0_TX_DP<13>
J 0
(-3290 4510);
DISPLAY 0.659574 (-3290 4510);
PAINT MONO (-3290 4510);
DISPLAY INVISIBLE (-3290 4510);
FORCEPROP 1 LASTPIN (-3300 4500) BN 13
J 2
(-3248 4508);
DISPLAY 0.680851 (-3248 4508);
PAINT MONO (-3248 4508);
FORCEPROP 2 LAST ROOM RISER1
J 0
(-3750 4550);
DISPLAY 0.829787 (-3750 4550);
PAINT RED (-3750 4550);
DISPLAY INVISIBLE (-3750 4550);
FORCEPROP 2 LAST BOM_COST IO_SLOT
J 0
(-3750 4600);
DISPLAY 0.829787 (-3750 4600);
DISPLAY INVISIBLE (-3750 4600);
FORCEPROP 2 LAST CDS_LIB standard
J 0
(-3250 4500);
DISPLAY INVISIBLE (-3250 4500);
FORCEPROP 1 LAST BODY_TYPE PLUMBING
J 2
(-3250 4450);
DISPLAY 0.702128 (-3250 4450);
PAINT GREEN (-3250 4450);
DISPLAY INVISIBLE (-3250 4450);
FORCEPROP 1 LAST HDL_TAP TRUE
J 2
(-3575 4375);
DISPLAY 0.702128 (-3575 4375);
PAINT GREEN (-3575 4375);
DISPLAY INVISIBLE (-3575 4375);
FORCEPROP 1 LAST PATH I384
J 2
(-3248 4500);
DISPLAY 0.872340 (-3248 4500);
PAINT GREEN (-3248 4500);
DISPLAY INVISIBLE (-3248 4500);
FORCEADD TAP..6
R 2
(-3250 4700);
FORCEPROP 3 LASTPIN (-3300 4700) SIG_NAME P5E_CPU0_P0_TX_DP<11>
J 0
(-3290 4710);
DISPLAY 0.659574 (-3290 4710);
PAINT MONO (-3290 4710);
DISPLAY INVISIBLE (-3290 4710);
FORCEPROP 1 LASTPIN (-3300 4700) BN 11
J 2
(-3248 4708);
DISPLAY 0.680851 (-3248 4708);
PAINT MONO (-3248 4708);
FORCEPROP 2 LAST ROOM RISER1
J 0
(-3750 4750);
DISPLAY 0.829787 (-3750 4750);
PAINT RED (-3750 4750);
DISPLAY INVISIBLE (-3750 4750);
FORCEPROP 2 LAST BOM_COST IO_SLOT
J 0
(-3750 4800);
DISPLAY 0.829787 (-3750 4800);
DISPLAY INVISIBLE (-3750 4800);
FORCEPROP 2 LAST CDS_LIB standard
J 0
(-3250 4700);
DISPLAY INVISIBLE (-3250 4700);
FORCEPROP 1 LAST BODY_TYPE PLUMBING
J 2
(-3250 4650);
DISPLAY 0.702128 (-3250 4650);
PAINT GREEN (-3250 4650);
DISPLAY INVISIBLE (-3250 4650);
FORCEPROP 1 LAST HDL_TAP TRUE
J 2
(-3575 4575);
DISPLAY 0.702128 (-3575 4575);
PAINT GREEN (-3575 4575);
DISPLAY INVISIBLE (-3575 4575);
FORCEPROP 1 LAST PATH I385
J 2
(-3248 4700);
DISPLAY 0.872340 (-3248 4700);
PAINT GREEN (-3248 4700);
DISPLAY INVISIBLE (-3248 4700);
FORCEADD TAP..6
R 2
(-3250 4600);
FORCEPROP 3 LASTPIN (-3300 4600) SIG_NAME P5E_CPU0_P0_TX_DP<12>
J 0
(-3290 4610);
DISPLAY 0.659574 (-3290 4610);
PAINT MONO (-3290 4610);
DISPLAY INVISIBLE (-3290 4610);
FORCEPROP 1 LASTPIN (-3300 4600) BN 12
J 2
(-3248 4608);
DISPLAY 0.680851 (-3248 4608);
PAINT MONO (-3248 4608);
FORCEPROP 2 LAST ROOM RISER1
J 0
(-3750 4650);
DISPLAY 0.829787 (-3750 4650);
PAINT RED (-3750 4650);
DISPLAY INVISIBLE (-3750 4650);
FORCEPROP 2 LAST BOM_COST IO_SLOT
J 0
(-3750 4700);
DISPLAY 0.829787 (-3750 4700);
DISPLAY INVISIBLE (-3750 4700);
FORCEPROP 2 LAST CDS_LIB standard
J 0
(-3250 4600);
DISPLAY INVISIBLE (-3250 4600);
FORCEPROP 1 LAST BODY_TYPE PLUMBING
J 2
(-3250 4550);
DISPLAY 0.702128 (-3250 4550);
PAINT GREEN (-3250 4550);
DISPLAY INVISIBLE (-3250 4550);
FORCEPROP 1 LAST HDL_TAP TRUE
J 2
(-3575 4475);
DISPLAY 0.702128 (-3575 4475);
PAINT GREEN (-3575 4475);
DISPLAY INVISIBLE (-3575 4475);
FORCEPROP 1 LAST PATH I386
J 2
(-3248 4600);
DISPLAY 0.872340 (-3248 4600);
PAINT GREEN (-3248 4600);
DISPLAY INVISIBLE (-3248 4600);
FORCEADD TAP..6
R 2
(-3100 4450);
FORCEPROP 3 LASTPIN (-3150 4450) SIG_NAME P5E_CPU0_P0_TX_DN<13>
J 0
(-3140 4460);
DISPLAY 0.659574 (-3140 4460);
PAINT MONO (-3140 4460);
DISPLAY INVISIBLE (-3140 4460);
FORCEPROP 1 LASTPIN (-3150 4450) BN 13
J 2
(-3098 4458);
DISPLAY 0.680851 (-3098 4458);
PAINT MONO (-3098 4458);
FORCEPROP 2 LAST ROOM RISER1
J 0
(-3600 4500);
DISPLAY 0.829787 (-3600 4500);
PAINT RED (-3600 4500);
DISPLAY INVISIBLE (-3600 4500);
FORCEPROP 2 LAST BOM_COST IO_SLOT
J 0
(-3600 4550);
DISPLAY 0.829787 (-3600 4550);
DISPLAY INVISIBLE (-3600 4550);
FORCEPROP 2 LAST CDS_LIB standard
J 0
(-3100 4450);
DISPLAY INVISIBLE (-3100 4450);
FORCEPROP 1 LAST BODY_TYPE PLUMBING
J 2
(-3100 4400);
DISPLAY 0.702128 (-3100 4400);
PAINT GREEN (-3100 4400);
DISPLAY INVISIBLE (-3100 4400);
FORCEPROP 1 LAST HDL_TAP TRUE
J 2
(-3425 4325);
DISPLAY 0.702128 (-3425 4325);
PAINT GREEN (-3425 4325);
DISPLAY INVISIBLE (-3425 4325);
FORCEPROP 1 LAST PATH I387
J 2
(-3098 4450);
DISPLAY 0.872340 (-3098 4450);
PAINT GREEN (-3098 4450);
DISPLAY INVISIBLE (-3098 4450);
FORCEADD TAP..6
R 2
(-3100 4250);
FORCEPROP 3 LASTPIN (-3150 4250) SIG_NAME P5E_CPU0_P0_TX_DN<15>
J 0
(-3140 4260);
DISPLAY 0.659574 (-3140 4260);
PAINT MONO (-3140 4260);
DISPLAY INVISIBLE (-3140 4260);
FORCEPROP 1 LASTPIN (-3150 4250) BN 15
J 2
(-3098 4258);
DISPLAY 0.680851 (-3098 4258);
PAINT MONO (-3098 4258);
FORCEPROP 2 LAST ROOM RISER1
J 0
(-3600 4300);
DISPLAY 0.829787 (-3600 4300);
PAINT RED (-3600 4300);
DISPLAY INVISIBLE (-3600 4300);
FORCEPROP 2 LAST BOM_COST IO_SLOT
J 0
(-3600 4350);
DISPLAY 0.829787 (-3600 4350);
DISPLAY INVISIBLE (-3600 4350);
FORCEPROP 2 LAST CDS_LIB standard
J 0
(-3100 4250);
DISPLAY INVISIBLE (-3100 4250);
FORCEPROP 1 LAST BODY_TYPE PLUMBING
J 2
(-3100 4200);
DISPLAY 0.702128 (-3100 4200);
PAINT GREEN (-3100 4200);
DISPLAY INVISIBLE (-3100 4200);
FORCEPROP 1 LAST HDL_TAP TRUE
J 2
(-3425 4125);
DISPLAY 0.702128 (-3425 4125);
PAINT GREEN (-3425 4125);
DISPLAY INVISIBLE (-3425 4125);
FORCEPROP 1 LAST PATH I388
J 2
(-3098 4250);
DISPLAY 0.872340 (-3098 4250);
PAINT GREEN (-3098 4250);
DISPLAY INVISIBLE (-3098 4250);
FORCEADD TAP..6
R 2
(-3100 4350);
FORCEPROP 3 LASTPIN (-3150 4350) SIG_NAME P5E_CPU0_P0_TX_DN<14>
J 0
(-3140 4360);
DISPLAY 0.659574 (-3140 4360);
PAINT MONO (-3140 4360);
DISPLAY INVISIBLE (-3140 4360);
FORCEPROP 1 LASTPIN (-3150 4350) BN 14
J 2
(-3098 4358);
DISPLAY 0.680851 (-3098 4358);
PAINT MONO (-3098 4358);
FORCEPROP 2 LAST ROOM RISER1
J 0
(-3600 4400);
DISPLAY 0.829787 (-3600 4400);
PAINT RED (-3600 4400);
DISPLAY INVISIBLE (-3600 4400);
FORCEPROP 2 LAST BOM_COST IO_SLOT
J 0
(-3600 4450);
DISPLAY 0.829787 (-3600 4450);
DISPLAY INVISIBLE (-3600 4450);
FORCEPROP 2 LAST CDS_LIB standard
J 0
(-3100 4350);
DISPLAY INVISIBLE (-3100 4350);
FORCEPROP 1 LAST BODY_TYPE PLUMBING
J 2
(-3100 4300);
DISPLAY 0.702128 (-3100 4300);
PAINT GREEN (-3100 4300);
DISPLAY INVISIBLE (-3100 4300);
FORCEPROP 1 LAST HDL_TAP TRUE
J 2
(-3425 4225);
DISPLAY 0.702128 (-3425 4225);
PAINT GREEN (-3425 4225);
DISPLAY INVISIBLE (-3425 4225);
FORCEPROP 1 LAST PATH I389
J 2
(-3098 4350);
DISPLAY 0.872340 (-3098 4350);
PAINT GREEN (-3098 4350);
DISPLAY INVISIBLE (-3098 4350);
FORCEADD TAP..6
R 2
(-3250 4400);
FORCEPROP 3 LASTPIN (-3300 4400) SIG_NAME P5E_CPU0_P0_TX_DP<14>
J 0
(-3290 4410);
DISPLAY 0.659574 (-3290 4410);
PAINT MONO (-3290 4410);
DISPLAY INVISIBLE (-3290 4410);
FORCEPROP 1 LASTPIN (-3300 4400) BN 14
J 2
(-3248 4408);
DISPLAY 0.680851 (-3248 4408);
PAINT MONO (-3248 4408);
FORCEPROP 2 LAST ROOM RISER1
J 0
(-3750 4450);
DISPLAY 0.829787 (-3750 4450);
PAINT RED (-3750 4450);
DISPLAY INVISIBLE (-3750 4450);
FORCEPROP 2 LAST BOM_COST IO_SLOT
J 0
(-3750 4500);
DISPLAY 0.829787 (-3750 4500);
DISPLAY INVISIBLE (-3750 4500);
FORCEPROP 2 LAST CDS_LIB standard
J 0
(-3250 4400);
DISPLAY INVISIBLE (-3250 4400);
FORCEPROP 1 LAST BODY_TYPE PLUMBING
J 2
(-3250 4350);
DISPLAY 0.702128 (-3250 4350);
PAINT GREEN (-3250 4350);
DISPLAY INVISIBLE (-3250 4350);
FORCEPROP 1 LAST HDL_TAP TRUE
J 2
(-3575 4275);
DISPLAY 0.702128 (-3575 4275);
PAINT GREEN (-3575 4275);
DISPLAY INVISIBLE (-3575 4275);
FORCEPROP 1 LAST PATH I390
J 2
(-3248 4400);
DISPLAY 0.872340 (-3248 4400);
PAINT GREEN (-3248 4400);
DISPLAY INVISIBLE (-3248 4400);
FORCEADD TAP..6
R 2
(-3250 4300);
FORCEPROP 3 LASTPIN (-3300 4300) SIG_NAME P5E_CPU0_P0_TX_DP<15>
J 0
(-3290 4310);
DISPLAY 0.659574 (-3290 4310);
PAINT MONO (-3290 4310);
DISPLAY INVISIBLE (-3290 4310);
FORCEPROP 1 LASTPIN (-3300 4300) BN 15
J 2
(-3248 4308);
DISPLAY 0.680851 (-3248 4308);
PAINT MONO (-3248 4308);
FORCEPROP 2 LAST ROOM RISER1
J 0
(-3750 4350);
DISPLAY 0.829787 (-3750 4350);
PAINT RED (-3750 4350);
DISPLAY INVISIBLE (-3750 4350);
FORCEPROP 2 LAST BOM_COST IO_SLOT
J 0
(-3750 4400);
DISPLAY 0.829787 (-3750 4400);
DISPLAY INVISIBLE (-3750 4400);
FORCEPROP 2 LAST CDS_LIB standard
J 0
(-3250 4300);
DISPLAY INVISIBLE (-3250 4300);
FORCEPROP 1 LAST BODY_TYPE PLUMBING
J 2
(-3250 4250);
DISPLAY 0.702128 (-3250 4250);
PAINT GREEN (-3250 4250);
DISPLAY INVISIBLE (-3250 4250);
FORCEPROP 1 LAST HDL_TAP TRUE
J 2
(-3575 4175);
DISPLAY 0.702128 (-3575 4175);
PAINT GREEN (-3575 4175);
DISPLAY INVISIBLE (-3575 4175);
FORCEPROP 1 LAST PATH I391
J 2
(-3248 4300);
DISPLAY 0.872340 (-3248 4300);
PAINT GREEN (-3248 4300);
DISPLAY INVISIBLE (-3248 4300);
FORCEADD OFFPAGE..2
(-1725 6025);
FORCEPROP 2 LAST $XR0 63 
J 0
(-1536 6025);
DISPLAY 0.638298 (-1536 6025);
PAINT MONO (-1536 6025);
FORCEPROP 2 LAST CDS_LIB standard
J 0
(-1725 6025);
DISPLAY INVISIBLE (-1725 6025);
FORCEPROP 1 LAST OFFPAGE TRUE
J 0
(-1400 5900);
DISPLAY 0.872340 (-1400 5900);
PAINT GREEN (-1400 5900);
DISPLAY INVISIBLE (-1400 5900);
FORCEPROP 1 LAST COMMENT_BODY TRUE
J 0
(-1770 5930);
DISPLAY 0.872340 (-1770 5930);
PAINT GREEN (-1770 5930);
DISPLAY INVISIBLE (-1770 5930);
FORCEPROP 2 LAST PATH I392
J 0
(-1550 6100);
DISPLAY 0.680851 (-1550 6100);
DISPLAY INVISIBLE (-1550 6100);
FORCEADD OFFPAGE..2
(-1725 5975);
FORCEPROP 2 LAST $XR0 63 
J 0
(-1536 5975);
DISPLAY 0.638298 (-1536 5975);
PAINT MONO (-1536 5975);
FORCEPROP 2 LAST CDS_LIB standard
J 0
(-1725 5975);
DISPLAY INVISIBLE (-1725 5975);
FORCEPROP 1 LAST OFFPAGE TRUE
J 0
(-1400 5850);
DISPLAY 0.872340 (-1400 5850);
PAINT GREEN (-1400 5850);
DISPLAY INVISIBLE (-1400 5850);
FORCEPROP 1 LAST COMMENT_BODY TRUE
J 0
(-1770 5880);
DISPLAY 0.872340 (-1770 5880);
PAINT GREEN (-1770 5880);
DISPLAY INVISIBLE (-1770 5880);
FORCEPROP 2 LAST PATH I393
J 0
(-1550 6050);
DISPLAY 0.680851 (-1550 6050);
DISPLAY INVISIBLE (-1550 6050);
FORCEADD QUANTA_TITLE_BLOCK_C..1
(-100 100);
FORCEPROP 0 LAST CDS_CON_LAST_MODIFIED Thu Sep 14 16:11:52 2023
J 0
(-1985 115);
DISPLAY INVISIBLE (-1985 115);
FORCEPROP 1 LAST CUSTOM_TXT_CDS <CON_LAST_MODIFIED>
J 0
(-1985 115);
DISPLAY 0.978723 (-1985 115);
FORCEPROP 2 LAST CUSTOM_TXT_CDS <XR_PAGE_TITLE>
J 0
(-7990 5350);
DISPLAY 0.638298 (-7990 5350);
PAINT PINK (-7990 5350);
DISPLAY INVISIBLE (-7990 5350);
FORCEPROP 1 LAST CUSTOM_TXT_CDS <NAME_2>
J 0
(-3275 150);
FORCEPROP 1 LAST CUSTOM_TXT_CDS <NAME_1>
J 0
(-3275 275);
FORCEPROP 1 LAST CUSTOM_TXT_CDS <Q_NUMBER>
J 0
(-1503 203);
DISPLAY 1.212766 (-1503 203);
FORCEPROP 1 LAST CUSTOM_TXT_CDS <Q_PROJ>
J 0
(-2482 202);
DISPLAY 1.212766 (-2482 202);
FORCEPROP 1 LAST CUSTOM_TXT_CDS <Q_REV>
J 0
(-284 203);
DISPLAY 1.212766 (-284 203);
FORCEPROP 1 LAST CUSTOM_TXT_CDS <CON_PAGE_NUM> OF <CON_TOTAL_PAGES>
J 0
(-546 118);
DISPLAY 0.978723 (-546 118);
FORCEPROP 1 LAST Q_TITLE CPU0 PCIE P0/P1
J 0
(-9400 150);
DISPLAY 2.446809 (-9400 150);
PAINT GREEN (-9400 150);
FORCEPROP 2 LAST PAGE_BORDER TRUE
J 0
(-7990 5350);
DISPLAY 0.638298 (-7990 5350);
PAINT PINK (-7990 5350);
DISPLAY INVISIBLE (-7990 5350);
FORCEPROP 1 LAST CDS_LMAN_SYM_OUTLINE -9475,6775,100,-125
J 0
(-100 100);
DISPLAY 0.468085 (-100 100);
PAINT GREEN (-100 100);
DISPLAY INVISIBLE (-100 100);
FORCEPROP 2 LAST CDS_LIB pure_quanta
J 0
(-100 100);
DISPLAY INVISIBLE (-100 100);
FORCEPROP 2 LAST CDS_XR_PAGE_TITLE CR-24 : @T6G_MB_LIB.T6G(SCH_1):PAGE24
J 0
(-7990 5350);
DISPLAY 0.638298 (-7990 5350);
PAINT PINK (-7990 5350);
DISPLAY INVISIBLE (-7990 5350);
FORCEPROP 1 LAST Q_DEPT BU9
J 1
(-3863 149);
DISPLAY 1.957447 (-3863 149);
PAINT GREEN (-3863 149);
DISPLAY INVISIBLE (-3863 149);
FORCEPROP 1 LAST COMMENT_BODY TRUE
J 0
(-88 87);
DISPLAY 0.978723 (-88 87);
PAINT GREEN (-88 87);
DISPLAY INVISIBLE (-88 87);
WIRE 17 -1 (-3275 2150)(-3275 2050);
WIRE 17 -1 (-3275 2250)(-3275 2150);
WIRE 17 -1 (-3275 2050)(-3275 1950);
WIRE 17 -1 (-3275 1950)(-3275 1850);
WIRE 17 -1 (-3275 2350)(-3275 2250);
WIRE 17 -1 (-3275 2550)(-3275 2350);
WIRE 17 -1 (-3275 1850)(-3275 1750);
WIRE 17 -1 (-3275 1750)(-3275 1650);
WIRE 17 -1 (-3275 2550)(-1850 2550);
FORCEPROP 2 LAST SIG_NAME P5E_CPU0_P1_TX_DP<15:0>
J 2
(-1875 2560);
DISPLAY 0.489362 (-1875 2560);
WIRE 17 -1 (-3125 2300)(-3125 2200);
WIRE 17 -1 (-3125 2500)(-3125 2300);
WIRE 17 -1 (-3125 2200)(-3125 2100);
WIRE 17 -1 (-3125 2100)(-3125 2000);
WIRE 17 -1 (-3125 2500)(-1850 2500);
FORCEPROP 2 LAST SIG_NAME P5E_CPU0_P1_TX_DN<15:0>
J 2
(-1875 2510);
DISPLAY 0.489362 (-1875 2510);
WIRE 17 -1 (-3125 2000)(-3125 1900);
WIRE 17 -1 (-3125 1400)(-3125 1300);
WIRE 17 -1 (-3125 1500)(-3125 1400);
WIRE 17 -1 (-3125 1300)(-3125 1200);
WIRE 17 -1 (-3125 1200)(-3125 1100);
WIRE 17 -1 (-3125 1600)(-3125 1500);
WIRE 17 -1 (-3125 1700)(-3125 1600);
WIRE 17 -1 (-3125 1100)(-3125 1000);
WIRE 17 -1 (-3125 1000)(-3125 900);
WIRE 17 -1 (-3125 1800)(-3125 1700);
WIRE 17 -1 (-3125 1900)(-3125 1800);
WIRE 17 -1 (-3125 900)(-3125 800);
WIRE 17 -1 (-3275 1250)(-3275 1150);
WIRE 17 -1 (-3275 1350)(-3275 1250);
WIRE 17 -1 (-3275 1150)(-3275 1050);
WIRE 17 -1 (-3275 1050)(-3275 950);
WIRE 17 -1 (-3275 1450)(-3275 1350);
WIRE 17 -1 (-3275 1550)(-3275 1450);
WIRE 17 -1 (-3275 950)(-3275 850);
WIRE 17 -1 (-3275 1650)(-3275 1550);
WIRE 17 -1 (-6800 2250)(-6800 2350);
WIRE 17 -1 (-6800 2150)(-6800 2250);
WIRE 17 -1 (-6800 2350)(-6800 2550);
WIRE 17 -1 (-8075 2550)(-6800 2550);
FORCEPROP 2 LAST SIG_NAME P5E_CPU0_P1_RX_DP<15:0>
J 0
(-8025 2560);
DISPLAY 0.489362 (-8025 2560);
WIRE 17 -1 (-6950 2300)(-6950 2500);
WIRE 17 -1 (-6950 2200)(-6950 2300);
WIRE 17 -1 (-8075 2500)(-6950 2500);
FORCEPROP 2 LAST SIG_NAME P5E_CPU0_P1_RX_DN<15:0>
J 0
(-8025 2510);
DISPLAY 0.489362 (-8025 2510);
WIRE 17 -1 (-3200 5825)(-3200 5725);
WIRE 17 -1 (-3200 6025)(-3200 5825);
WIRE 17 -1 (-3200 5725)(-3200 5625);
WIRE 17 -1 (-3200 5625)(-3200 5525);
WIRE 17 -1 (-3200 6025)(-1775 6025);
FORCEPROP 2 LAST SIG_NAME P5E_CPU0_P0_TX_DP<15:0>
J 0
(-2810 6060);
DISPLAY 0.489362 (-2810 6060);
WIRE 17 -1 (-3200 4925)(-3200 4825);
WIRE 17 -1 (-3200 5025)(-3200 4925);
WIRE 17 -1 (-3200 4825)(-3200 4725);
WIRE 17 -1 (-3200 4725)(-3200 4625);
WIRE 17 -1 (-3200 5125)(-3200 5025);
WIRE 17 -1 (-3200 5225)(-3200 5125);
WIRE 17 -1 (-3200 4625)(-3200 4525);
WIRE 17 -1 (-3200 4525)(-3200 4425);
WIRE 17 -1 (-3200 5325)(-3200 5225);
WIRE 17 -1 (-3200 5425)(-3200 5325);
WIRE 17 -1 (-3200 4425)(-3200 4325);
WIRE 17 -1 (-3200 5525)(-3200 5425);
WIRE 17 -1 (-6950 1800)(-6950 1900);
WIRE 17 -1 (-6950 1700)(-6950 1800);
WIRE 17 -1 (-6950 1900)(-6950 2000);
WIRE 17 -1 (-6950 2000)(-6950 2100);
WIRE 17 -1 (-6950 1600)(-6950 1700);
WIRE 17 -1 (-6950 1500)(-6950 1600);
WIRE 17 -1 (-6950 2100)(-6950 2200);
WIRE 17 -1 (-6950 1400)(-6950 1500);
WIRE 17 -1 (-6950 1300)(-6950 1400);
WIRE 17 -1 (-6950 900)(-6950 1000);
WIRE 17 -1 (-6950 800)(-6950 900);
WIRE 17 -1 (-6950 1000)(-6950 1100);
WIRE 17 -1 (-6950 1100)(-6950 1200);
WIRE 17 -1 (-6950 1200)(-6950 1300);
WIRE 17 -1 (-6800 950)(-6800 1050);
WIRE 17 -1 (-6800 850)(-6800 950);
WIRE 17 -1 (-6800 1050)(-6800 1150);
WIRE 17 -1 (-6800 1150)(-6800 1250);
WIRE 17 -1 (-6800 1250)(-6800 1350);
WIRE 17 -1 (-6800 1350)(-6800 1450);
WIRE 17 -1 (-6800 1450)(-6800 1550);
WIRE 17 -1 (-6800 1550)(-6800 1650);
WIRE 17 -1 (-6800 1650)(-6800 1750);
WIRE 17 -1 (-6800 1750)(-6800 1850);
WIRE 17 -1 (-6800 1850)(-6800 1950);
WIRE 17 -1 (-6800 1950)(-6800 2050);
WIRE 17 -1 (-6800 2050)(-6800 2150);
WIRE 17 -1 (-6725 4625)(-6725 4725);
WIRE 17 -1 (-6725 4525)(-6725 4625);
WIRE 17 -1 (-6725 4725)(-6725 4825);
WIRE 17 -1 (-6725 4825)(-6725 4925);
WIRE 17 -1 (-6725 4425)(-6725 4525);
WIRE 17 -1 (-6725 4325)(-6725 4425);
WIRE 17 -1 (-6725 4925)(-6725 5025);
WIRE 17 -1 (-6725 5025)(-6725 5125);
WIRE 17 -1 (-6725 5125)(-6725 5225);
WIRE 17 -1 (-6725 5225)(-6725 5325);
WIRE 17 -1 (-6725 5325)(-6725 5425);
WIRE 17 -1 (-6725 5425)(-6725 5525);
WIRE 17 -1 (-6725 5525)(-6725 5625);
WIRE 17 -1 (-6725 5625)(-6725 5725);
WIRE 17 -1 (-6725 5725)(-6725 5825);
WIRE 17 -1 (-6725 5825)(-6725 6025);
WIRE 17 -1 (-8000 6025)(-6725 6025);
FORCEPROP 2 LAST SIG_NAME P5E_CPU0_P0_RX_DP<15:0>
J 0
(-7735 6060);
DISPLAY 0.489362 (-7735 6060);
WIRE 17 -1 (-6875 4575)(-6875 4675);
WIRE 17 -1 (-6875 4475)(-6875 4575);
WIRE 17 -1 (-6875 4675)(-6875 4775);
WIRE 17 -1 (-6875 4775)(-6875 4875);
WIRE 17 -1 (-6875 4375)(-6875 4475);
WIRE 17 -1 (-6875 4275)(-6875 4375);
WIRE 17 -1 (-6875 4875)(-6875 4975);
WIRE 17 -1 (-6875 4975)(-6875 5075);
WIRE 17 -1 (-6875 5075)(-6875 5175);
WIRE 17 -1 (-6875 5175)(-6875 5275);
WIRE 17 -1 (-6875 5275)(-6875 5375);
WIRE 17 -1 (-6875 5375)(-6875 5475);
WIRE 17 -1 (-6875 5475)(-6875 5575);
WIRE 17 -1 (-6875 5575)(-6875 5675);
WIRE 17 -1 (-6875 5675)(-6875 5775);
WIRE 17 -1 (-6875 5775)(-6875 5975);
WIRE 17 -1 (-8000 5975)(-6875 5975);
FORCEPROP 2 LAST SIG_NAME P5E_CPU0_P0_RX_DN<15:0>
J 0
(-7735 5985);
DISPLAY 0.489362 (-7735 5985);
WIRE 17 -1 (-3050 4675)(-3050 4575);
WIRE 17 -1 (-3050 4775)(-3050 4675);
WIRE 17 -1 (-3050 4575)(-3050 4475);
WIRE 17 -1 (-3050 4475)(-3050 4375);
WIRE 17 -1 (-3050 4875)(-3050 4775);
WIRE 17 -1 (-3050 4975)(-3050 4875);
WIRE 17 -1 (-3050 4375)(-3050 4275);
WIRE 17 -1 (-3050 5075)(-3050 4975);
WIRE 17 -1 (-3050 5175)(-3050 5075);
WIRE 17 -1 (-3050 5275)(-3050 5175);
WIRE 17 -1 (-3050 5375)(-3050 5275);
WIRE 17 -1 (-3050 5475)(-3050 5375);
WIRE 17 -1 (-3050 5575)(-3050 5475);
WIRE 17 -1 (-3050 5675)(-3050 5575);
WIRE 17 -1 (-3050 5775)(-3050 5675);
WIRE 17 -1 (-3050 5975)(-3050 5775);
WIRE 17 -1 (-3050 5975)(-1775 5975);
FORCEPROP 2 LAST SIG_NAME P5E_CPU0_P0_TX_DN<15:0>
J 0
(-2810 5985);
DISPLAY 0.489362 (-2810 5985);
WIRE 16 -1 (-3675 4700)(-3300 4700);
WIRE 16 -1 (-3675 5750)(-3150 5750);
WIRE 16 -1 (-3675 4850)(-3150 4850);
WIRE 16 -1 (-3675 4950)(-3150 4950);
WIRE 16 -1 (-3675 5050)(-3150 5050);
WIRE 16 -1 (-3675 5150)(-3150 5150);
WIRE 16 -1 (-3675 5250)(-3150 5250);
WIRE 16 -1 (-3675 5450)(-3150 5450);
WIRE 16 -1 (-3675 4650)(-3150 4650);
WIRE 16 -1 (-3675 4350)(-3150 4350);
WIRE 16 -1 (-3675 4750)(-3150 4750);
WIRE 16 -1 (-3675 5650)(-3150 5650);
WIRE 16 -1 (-3675 5350)(-3150 5350);
WIRE 16 -1 (-3150 4250)(-3675 4250);
WIRE 16 -1 (-3675 4450)(-3150 4450);
WIRE 16 -1 (-3675 5550)(-3150 5550);
WIRE 16 -1 (-3675 4550)(-3150 4550);
WIRE 16 -1 (-3675 4400)(-3300 4400);
WIRE 16 -1 (-6775 4950)(-6175 4950);
WIRE 16 -1 (-6625 4900)(-6175 4900);
WIRE 16 -1 (-3675 4300)(-3300 4300);
WIRE 16 -1 (-3675 4600)(-3300 4600);
WIRE 16 -1 (-3750 1775)(-3225 1775);
WIRE 16 -1 (-3675 5500)(-3300 5500);
WIRE 16 -1 (-3675 5400)(-3300 5400);
WIRE 16 -1 (-3750 2125)(-3375 2125);
WIRE 16 -1 (-3675 5600)(-3300 5600);
WIRE 16 -1 (-6775 5750)(-6175 5750);
WIRE 16 -1 (-6625 5700)(-6175 5700);
WIRE 16 -1 (-6775 5650)(-6175 5650);
WIRE 16 -1 (-6775 4350)(-6175 4350);
WIRE 16 -1 (-6625 5800)(-6175 5800);
WIRE 16 -1 (-6775 5450)(-6175 5450);
WIRE 16 -1 (-6625 5500)(-6175 5500);
WIRE 16 -1 (-6775 5550)(-6175 5550);
WIRE 16 -1 (-6625 5600)(-6175 5600);
WIRE 16 -1 (-6775 4250)(-6175 4250);
WIRE 16 -1 (-6625 4300)(-6175 4300);
WIRE 16 -1 (-6775 4450)(-6175 4450);
WIRE 16 -1 (-6625 4600)(-6175 4600);
WIRE 16 -1 (-6625 4800)(-6175 4800);
WIRE 16 -1 (-6775 5150)(-6175 5150);
WIRE 16 -1 (-6625 5100)(-6175 5100);
WIRE 16 -1 (-6625 5400)(-6175 5400);
WIRE 16 -1 (-6775 5350)(-6175 5350);
WIRE 16 -1 (-6775 5050)(-6175 5050);
WIRE 16 -1 (-6625 5300)(-6175 5300);
WIRE 16 -1 (-6775 5250)(-6175 5250);
WIRE 16 -1 (-6625 5200)(-6175 5200);
WIRE 16 -1 (-6625 4400)(-6175 4400);
WIRE 16 -1 (-6625 5000)(-6175 5000);
WIRE 16 -1 (-6775 4550)(-6175 4550);
WIRE 16 -1 (-6775 4750)(-6175 4750);
WIRE 16 -1 (-6775 4850)(-6175 4850);
WIRE 16 -1 (-6625 4500)(-6175 4500);
WIRE 16 -1 (-6775 4650)(-6175 4650);
WIRE 16 -1 (-6625 4700)(-6175 4700);
WIRE 16 -1 (-3750 1675)(-3225 1675);
WIRE 16 -1 (-3750 1575)(-3225 1575);
WIRE 16 -1 (-3750 1825)(-3375 1825);
WIRE 16 -1 (-3750 1625)(-3375 1625);
WIRE 16 -1 (-3750 1725)(-3375 1725);
WIRE 16 -1 (-3750 1475)(-3225 1475);
WIRE 16 -1 (-3750 1375)(-3225 1375);
WIRE 16 -1 (-3750 1325)(-3375 1325);
WIRE 16 -1 (-3750 1425)(-3375 1425);
WIRE 16 -1 (-3750 1525)(-3375 1525);
WIRE 16 -1 (-3750 1225)(-3375 1225);
WIRE 16 -1 (-3750 975)(-3225 975);
WIRE 16 -1 (-3225 775)(-3750 775);
WIRE 16 -1 (-3750 925)(-3375 925);
WIRE 16 -1 (-3750 825)(-3375 825);
WIRE 16 -1 (-6850 975)(-6250 975);
WIRE 16 -1 (-6700 825)(-6250 825);
WIRE 16 -1 (-6700 2125)(-6250 2125);
WIRE 16 -1 (-6850 2075)(-6250 2075);
WIRE 16 -1 (-6850 2175)(-6250 2175);
WIRE 16 -1 (-6700 2025)(-6250 2025);
WIRE 16 -1 (-6700 1925)(-6250 1925);
WIRE 16 -1 (-6700 1825)(-6250 1825);
WIRE 16 -1 (-6700 1725)(-6250 1725);
WIRE 16 -1 (-6700 1625)(-6250 1625);
WIRE 16 -1 (-6850 1675)(-6250 1675);
WIRE 16 -1 (-6850 1575)(-6250 1575);
WIRE 16 -1 (-6700 1525)(-6250 1525);
WIRE 16 -1 (-6700 1425)(-6250 1425);
WIRE 16 -1 (-6700 1325)(-6250 1325);
WIRE 16 -1 (-6700 1225)(-6250 1225);
WIRE 16 -1 (-6700 1025)(-6250 1025);
WIRE 16 -1 (-6700 1125)(-6250 1125);
WIRE 16 -1 (-6850 1475)(-6250 1475);
WIRE 16 -1 (-6850 1375)(-6250 1375);
WIRE 16 -1 (-6850 1275)(-6250 1275);
WIRE 16 -1 (-6850 1175)(-6250 1175);
WIRE 16 -1 (-6850 1075)(-6250 1075);
WIRE 16 -1 (-6700 925)(-6250 925);
WIRE 16 -1 (-6850 775)(-6250 775);
WIRE 16 -1 (-6850 875)(-6250 875);
WIRE 16 -1 (-6850 1975)(-6250 1975);
WIRE 16 -1 (-6850 1875)(-6250 1875);
WIRE 16 -1 (-6850 1775)(-6250 1775);
WIRE 16 -1 (-3750 1975)(-3225 1975);
WIRE 16 -1 (-3750 1875)(-3225 1875);
WIRE 16 -1 (-3750 1925)(-3375 1925);
WIRE 16 -1 (-3675 4500)(-3300 4500);
WIRE 16 -1 (-3675 5100)(-3300 5100);
WIRE 16 -1 (-3675 5200)(-3300 5200);
WIRE 16 -1 (-3675 5300)(-3300 5300);
WIRE 16 -1 (-3675 5000)(-3300 5000);
WIRE 16 -1 (-3675 4900)(-3300 4900);
WIRE 16 -1 (-3675 4800)(-3300 4800);
WIRE 16 -1 (-3675 5800)(-3300 5800);
WIRE 16 -1 (-3675 5700)(-3300 5700);
WIRE 16 -1 (-6700 2325)(-6250 2325);
WIRE 16 -1 (-6850 2275)(-6250 2275);
WIRE 16 -1 (-6700 2225)(-6250 2225);
WIRE 16 -1 (-3750 2325)(-3375 2325);
WIRE 16 -1 (-3750 2225)(-3375 2225);
WIRE 16 -1 (-3750 2275)(-3225 2275);
WIRE 16 -1 (-3750 875)(-3225 875);
WIRE 16 -1 (-3750 1025)(-3375 1025);
WIRE 16 -1 (-3750 1075)(-3225 1075);
WIRE 16 -1 (-3750 1125)(-3375 1125);
WIRE 16 -1 (-3750 1175)(-3225 1175);
WIRE 16 -1 (-3750 1275)(-3225 1275);
WIRE 16 -1 (-3750 2075)(-3225 2075);
WIRE 16 -1 (-3750 2175)(-3225 2175);
WIRE 16 -1 (-3750 2025)(-3375 2025);
FORCENOTE
CPU0 P1[15:0] TO EXAMAX
(-2775 1475) 0;
DISPLAY LEFT (-2775 1475);
DISPLAY 2.000000 (-2775 1475);
FORCENOTE
CPU0 P0[15:0] TO EXAMAX
(-2650 5100) 0;
DISPLAY LEFT (-2650 5100);
DISPLAY 2.000000 (-2650 5100);
QUIT
